G04 ================== begin FILE IDENTIFICATION RECORD ==================*
G04 Layout Name:  D:/<user>/Wistron_project/16317-1/gbr/16317-1.brd*
G04 Film Name:    SE_REF_L6*
G04 File Format:  Gerber RS274X*
G04 File Origin:  Cadence Allegro 16.5-S056*
G04 Origin Date:  Fri Jun 09 15:54:08 2017*
G04 *
G04 Layer:  BOARD GEOMETRY/SE_REF_L6_TBL*
G04 Layer:  BOARD GEOMETRY/SE_REF_L6_L6*
G04 Layer:  BOARD GEOMETRY/PANEL_OUTLINE*
G04 *
G04 Offset:    (0.00 0.00)*
G04 Mirror:    No*
G04 Mode:      Positive*
G04 Rotation:  0*
G04 FullContactRelief:  No*
G04 UndefLineWidth:     6.00*
G04 ================== end FILE IDENTIFICATION RECORD ====================*
%FSLAX35Y35*MOIN*%
%IR0*IPPOS*OFA0.00000B0.00000*MIA0B0*SFA1.00000B1.00000*%
%ADD10C,.02*%
%ADD11C,.006*%
%ADD12C,.00575*%
G75*
%LPD*%
G75*
G54D10*
G01X1985143Y1416035D02*
X2720143D01*
G01X1985143Y1485335D02*
Y1416035D01*
G01Y1485335D02*
X2720143D01*
G01X1985143Y1450685D02*
X2720143D01*
G01X2160143Y1485335D02*
Y1416035D01*
G01X2405143Y1485335D02*
Y1416035D01*
G01X2510143Y1485335D02*
Y1416035D01*
G01X2720143Y1485335D02*
Y1416035D01*
G54D11*
G01X6250Y-33194D02*
Y-50694D01*
G01X1228Y-33194D02*
X11272D01*
G01X20038Y-50694D02*
Y-33194D01*
G01Y-41652D02*
X21130Y-40194D01*
X22222Y-39319D01*
X23968Y-39028D01*
X25278Y-39319D01*
X26807Y-40486D01*
X27462Y-42236D01*
Y-50694D01*
G01X41250Y-39028D02*
Y-50694D01*
G01Y-34361D02*
X40813Y-34069D01*
Y-33486D01*
X41250Y-33194D01*
X41687Y-33486D01*
Y-34069D01*
X41250Y-34361D01*
G01X55475Y-48653D02*
X56567Y-49819D01*
X58095Y-50694D01*
X59405D01*
X60715Y-50111D01*
X61588Y-49236D01*
X62025Y-48070D01*
X61807Y-46319D01*
X60933Y-45444D01*
X57003Y-43694D01*
X56130Y-41652D01*
X56567Y-40194D01*
X57440Y-39319D01*
X58750Y-39028D01*
X60060Y-39319D01*
X61370Y-40194D01*
G01X90693Y-55069D02*
X92222Y-56236D01*
X93968Y-56527D01*
X95496Y-56236D01*
X96807Y-54778D01*
X97680Y-52736D01*
Y-39028D01*
G01Y-41361D02*
X96807Y-40194D01*
X95496Y-39319D01*
X93968Y-39028D01*
X92222Y-39611D01*
X91130Y-40777D01*
X90256Y-42819D01*
X89820Y-44861D01*
X90038Y-46611D01*
X90912Y-48653D01*
X92222Y-50111D01*
X93968Y-50694D01*
X95278Y-50402D01*
X96807Y-49236D01*
X97680Y-48070D01*
G01X107975Y-42819D02*
X114962D01*
X114307Y-40777D01*
X113215Y-39611D01*
X111687Y-39028D01*
X110158Y-39319D01*
X108848Y-40194D01*
X107975Y-42236D01*
X107538Y-43986D01*
Y-45736D01*
X107975Y-47486D01*
X109067Y-49236D01*
X110377Y-50402D01*
X111905Y-50694D01*
X113433Y-50111D01*
X114962Y-48361D01*
G01X125693Y-50694D02*
Y-39028D01*
G01Y-41361D02*
X126785Y-40194D01*
X127877Y-39319D01*
X129405Y-39028D01*
X130496Y-39319D01*
X131807Y-40194D01*
G01X142320Y-50694D02*
Y-33194D01*
G01Y-41944D02*
X143412Y-40194D01*
X144722Y-39319D01*
X146032Y-39028D01*
X147996Y-39611D01*
X149307Y-40777D01*
X150180Y-42819D01*
Y-45152D01*
X149743Y-47486D01*
X148870Y-49236D01*
X147342Y-50402D01*
X146032Y-50694D01*
X144722Y-50402D01*
X143412Y-49528D01*
X142320Y-48070D01*
G01X160475Y-42819D02*
X167462D01*
X166807Y-40777D01*
X165715Y-39611D01*
X164187Y-39028D01*
X162658Y-39319D01*
X161348Y-40194D01*
X160475Y-42236D01*
X160038Y-43986D01*
Y-45736D01*
X160475Y-47486D01*
X161567Y-49236D01*
X162877Y-50402D01*
X164405Y-50694D01*
X165933Y-50111D01*
X167462Y-48361D01*
G01X178193Y-50694D02*
Y-39028D01*
G01Y-41361D02*
X179285Y-40194D01*
X180377Y-39319D01*
X181905Y-39028D01*
X182996Y-39319D01*
X184307Y-40194D01*
G01X216250Y-39028D02*
Y-50694D01*
G01Y-34361D02*
X215813Y-34069D01*
Y-33486D01*
X216250Y-33194D01*
X216687Y-33486D01*
Y-34069D01*
X216250Y-34361D01*
G01X230475Y-48653D02*
X231567Y-49819D01*
X233095Y-50694D01*
X234405D01*
X235715Y-50111D01*
X236588Y-49236D01*
X237025Y-48070D01*
X236807Y-46319D01*
X235933Y-45444D01*
X232003Y-43694D01*
X231130Y-41652D01*
X231567Y-40194D01*
X232440Y-39319D01*
X233750Y-39028D01*
X235060Y-39319D01*
X236370Y-40194D01*
G01X265256Y-55069D02*
X266785Y-56236D01*
X268095Y-56527D01*
X269842Y-55944D01*
X271152Y-54486D01*
X271807Y-51860D01*
Y-39028D01*
G01Y-34361D02*
X271370Y-34069D01*
Y-33486D01*
X271807Y-33194D01*
X272243Y-33486D01*
Y-34069D01*
X271807Y-34361D01*
G01X282538Y-39028D02*
Y-47194D01*
X283412Y-49236D01*
X284722Y-50402D01*
X286250Y-50694D01*
X287778Y-50402D01*
X289088Y-49236D01*
X289962Y-47194D01*
G01Y-50694D02*
Y-39028D01*
G01X300475Y-48653D02*
X301567Y-49819D01*
X303095Y-50694D01*
X304405D01*
X305715Y-50111D01*
X306588Y-49236D01*
X307025Y-48070D01*
X306807Y-46319D01*
X305933Y-45444D01*
X302003Y-43694D01*
X301130Y-41652D01*
X301567Y-40194D01*
X302440Y-39319D01*
X303750Y-39028D01*
X305060Y-39319D01*
X306370Y-40194D01*
G01X321250Y-33194D02*
Y-50694D01*
G01X318193Y-39028D02*
X324307D01*
G01X354940Y-50694D02*
Y-35819D01*
X355377Y-34361D01*
X356250Y-33486D01*
X357560Y-33194D01*
X358870Y-33777D01*
X359525Y-35236D01*
G01X356905Y-40194D02*
X352538D01*
G01X373750Y-50694D02*
X372440Y-50402D01*
X371130Y-49236D01*
X370256Y-47194D01*
X369820Y-44861D01*
X370256Y-42527D01*
X371130Y-40486D01*
X372440Y-39319D01*
X373750Y-39028D01*
X375060Y-39319D01*
X376370Y-40486D01*
X377243Y-42527D01*
X377462Y-44861D01*
X377243Y-47194D01*
X376370Y-49236D01*
X375060Y-50402D01*
X373750Y-50694D01*
G01X388193D02*
Y-39028D01*
G01Y-41361D02*
X389285Y-40194D01*
X390377Y-39319D01*
X391905Y-39028D01*
X392996Y-39319D01*
X394307Y-40194D01*
G01X421665Y-55944D02*
X422975Y-56527D01*
X424722Y-55944D01*
X425813Y-54778D01*
X426687Y-53319D01*
X427996Y-48653D01*
X430835Y-39028D01*
G01X423848D02*
X427996Y-48653D01*
G01X443750Y-50694D02*
X442440Y-50402D01*
X441130Y-49236D01*
X440256Y-47194D01*
X439820Y-44861D01*
X440256Y-42527D01*
X441130Y-40486D01*
X442440Y-39319D01*
X443750Y-39028D01*
X445060Y-39319D01*
X446370Y-40486D01*
X447243Y-42527D01*
X447462Y-44861D01*
X447243Y-47194D01*
X446370Y-49236D01*
X445060Y-50402D01*
X443750Y-50694D01*
G01X457538Y-39028D02*
Y-47194D01*
X458412Y-49236D01*
X459722Y-50402D01*
X461250Y-50694D01*
X462778Y-50402D01*
X464088Y-49236D01*
X464962Y-47194D01*
G01Y-50694D02*
Y-39028D01*
G01X475693Y-50694D02*
Y-39028D01*
G01Y-41361D02*
X476785Y-40194D01*
X477877Y-39319D01*
X479405Y-39028D01*
X480496Y-39319D01*
X481807Y-40194D01*
G01X510693Y-50694D02*
Y-39028D01*
G01Y-41361D02*
X511785Y-40194D01*
X512877Y-39319D01*
X514405Y-39028D01*
X515496Y-39319D01*
X516807Y-40194D01*
G01X527975Y-42819D02*
X534962D01*
X534307Y-40777D01*
X533215Y-39611D01*
X531687Y-39028D01*
X530158Y-39319D01*
X528848Y-40194D01*
X527975Y-42236D01*
X527538Y-43986D01*
Y-45736D01*
X527975Y-47486D01*
X529067Y-49236D01*
X530377Y-50402D01*
X531905Y-50694D01*
X533433Y-50111D01*
X534962Y-48361D01*
G01X547440Y-50694D02*
Y-35819D01*
X547877Y-34361D01*
X548750Y-33486D01*
X550060Y-33194D01*
X551370Y-33777D01*
X552025Y-35236D01*
G01X549405Y-40194D02*
X545038D01*
G01X562975Y-42819D02*
X569962D01*
X569307Y-40777D01*
X568215Y-39611D01*
X566687Y-39028D01*
X565158Y-39319D01*
X563848Y-40194D01*
X562975Y-42236D01*
X562538Y-43986D01*
Y-45736D01*
X562975Y-47486D01*
X564067Y-49236D01*
X565377Y-50402D01*
X566905Y-50694D01*
X568433Y-50111D01*
X569962Y-48361D01*
G01X580693Y-50694D02*
Y-39028D01*
G01Y-41361D02*
X581785Y-40194D01*
X582877Y-39319D01*
X584405Y-39028D01*
X585496Y-39319D01*
X586807Y-40194D01*
G01X597975Y-42819D02*
X604962D01*
X604307Y-40777D01*
X603215Y-39611D01*
X601687Y-39028D01*
X600158Y-39319D01*
X598848Y-40194D01*
X597975Y-42236D01*
X597538Y-43986D01*
Y-45736D01*
X597975Y-47486D01*
X599067Y-49236D01*
X600377Y-50402D01*
X601905Y-50694D01*
X603433Y-50111D01*
X604962Y-48361D01*
G01X615038Y-50694D02*
Y-39028D01*
G01Y-41944D02*
X615912Y-40486D01*
X617222Y-39319D01*
X618968Y-39028D01*
X620496Y-39319D01*
X621807Y-40486D01*
X622462Y-42527D01*
Y-50694D01*
G01X639743Y-40486D02*
X638215Y-39319D01*
X636905Y-39028D01*
X635158Y-39611D01*
X633848Y-40777D01*
X632975Y-42819D01*
X632756Y-44861D01*
X632975Y-46903D01*
X633848Y-48653D01*
X635158Y-50111D01*
X636905Y-50694D01*
X638433Y-50111D01*
X639743Y-48944D01*
G01X650475Y-42819D02*
X657462D01*
X656807Y-40777D01*
X655715Y-39611D01*
X654187Y-39028D01*
X652658Y-39319D01*
X651348Y-40194D01*
X650475Y-42236D01*
X650038Y-43986D01*
Y-45736D01*
X650475Y-47486D01*
X651567Y-49236D01*
X652877Y-50402D01*
X654405Y-50694D01*
X655933Y-50111D01*
X657462Y-48361D01*
G01X688750Y-33194D02*
Y-50694D01*
G01X685693Y-39028D02*
X691807D01*
G01X706250Y-50694D02*
X704940Y-50402D01*
X703630Y-49236D01*
X702756Y-47194D01*
X702320Y-44861D01*
X702756Y-42527D01*
X703630Y-40486D01*
X704940Y-39319D01*
X706250Y-39028D01*
X707560Y-39319D01*
X708870Y-40486D01*
X709743Y-42527D01*
X709962Y-44861D01*
X709743Y-47194D01*
X708870Y-49236D01*
X707560Y-50402D01*
X706250Y-50694D01*
G01X739940D02*
Y-35819D01*
X740377Y-34361D01*
X741250Y-33486D01*
X742560Y-33194D01*
X743870Y-33777D01*
X744525Y-35236D01*
G01X741905Y-40194D02*
X737538D01*
G01X758750Y-39028D02*
Y-50694D01*
G01Y-34361D02*
X758313Y-34069D01*
Y-33486D01*
X758750Y-33194D01*
X759187Y-33486D01*
Y-34069D01*
X758750Y-34361D01*
G01X772538Y-50694D02*
Y-39028D01*
G01Y-41944D02*
X773412Y-40486D01*
X774722Y-39319D01*
X776468Y-39028D01*
X777996Y-39319D01*
X779307Y-40486D01*
X779962Y-42527D01*
Y-50694D01*
G01X797680Y-33194D02*
Y-50694D01*
G01Y-48070D02*
X796807Y-49528D01*
X795496Y-50402D01*
X793968Y-50694D01*
X792222Y-50111D01*
X790912Y-48653D01*
X790038Y-46903D01*
X789820Y-44861D01*
X790038Y-42819D01*
X790912Y-41069D01*
X792222Y-39611D01*
X793968Y-39028D01*
X795496Y-39319D01*
X796588Y-39903D01*
X797680Y-41069D01*
G01X828750Y-33194D02*
Y-50694D01*
G01X825693Y-39028D02*
X831807D01*
G01X842538Y-50694D02*
Y-33194D01*
G01Y-41652D02*
X843630Y-40194D01*
X844722Y-39319D01*
X846468Y-39028D01*
X847778Y-39319D01*
X849307Y-40486D01*
X849962Y-42236D01*
Y-50694D01*
G01X860475Y-42819D02*
X867462D01*
X866807Y-40777D01*
X865715Y-39611D01*
X864187Y-39028D01*
X862658Y-39319D01*
X861348Y-40194D01*
X860475Y-42236D01*
X860038Y-43986D01*
Y-45736D01*
X860475Y-47486D01*
X861567Y-49236D01*
X862877Y-50402D01*
X864405Y-50694D01*
X865933Y-50111D01*
X867462Y-48361D01*
G01X894165D02*
X895912Y-49819D01*
X897877Y-50694D01*
X899623D01*
X901370Y-49819D01*
X902680Y-48361D01*
X903335Y-46319D01*
X902898Y-44278D01*
X901807Y-42527D01*
X899842Y-41361D01*
X897222Y-40777D01*
X895693Y-39611D01*
X895038Y-37569D01*
X895475Y-35527D01*
X896567Y-34069D01*
X898095Y-33194D01*
X899623D01*
X901152Y-33777D01*
X902462Y-35236D01*
G01X920617Y-50694D02*
X911883D01*
Y-33194D01*
X920617D01*
G01X917123Y-41652D02*
X911883D01*
G01X951250Y-39028D02*
Y-50694D01*
G01Y-34361D02*
X950813Y-34069D01*
Y-33486D01*
X951250Y-33194D01*
X951687Y-33486D01*
Y-34069D01*
X951250Y-34361D01*
G01X962200Y-50694D02*
Y-39028D01*
G01Y-42236D02*
X962855Y-40777D01*
X963947Y-39611D01*
X965475Y-39028D01*
X967003Y-39611D01*
X968095Y-40777D01*
X968750Y-42236D01*
Y-50694D01*
G01Y-42236D02*
X969405Y-40777D01*
X970496Y-39611D01*
X972025Y-39028D01*
X973553Y-39611D01*
X974645Y-40777D01*
X975300Y-42527D01*
Y-50694D01*
G01X982320Y-56527D02*
Y-39028D01*
G01Y-41652D02*
X983412Y-40194D01*
X984503Y-39319D01*
X986250Y-39028D01*
X987778Y-39319D01*
X989307Y-40777D01*
X989962Y-42819D01*
X990180Y-44861D01*
X989962Y-46903D01*
X989307Y-48944D01*
X987996Y-50111D01*
X986250Y-50694D01*
X984722Y-50402D01*
X983193Y-49528D01*
X982320Y-48361D01*
G01X1000475Y-42819D02*
X1007462D01*
X1006807Y-40777D01*
X1005715Y-39611D01*
X1004187Y-39028D01*
X1002658Y-39319D01*
X1001348Y-40194D01*
X1000475Y-42236D01*
X1000038Y-43986D01*
Y-45736D01*
X1000475Y-47486D01*
X1001567Y-49236D01*
X1002877Y-50402D01*
X1004405Y-50694D01*
X1005933Y-50111D01*
X1007462Y-48361D01*
G01X1025180Y-33194D02*
Y-50694D01*
G01Y-48070D02*
X1024307Y-49528D01*
X1022996Y-50402D01*
X1021468Y-50694D01*
X1019722Y-50111D01*
X1018412Y-48653D01*
X1017538Y-46903D01*
X1017320Y-44861D01*
X1017538Y-42819D01*
X1018412Y-41069D01*
X1019722Y-39611D01*
X1021468Y-39028D01*
X1022996Y-39319D01*
X1024088Y-39903D01*
X1025180Y-41069D01*
G01X1042680Y-50694D02*
Y-39028D01*
G01Y-41069D02*
X1041807Y-39903D01*
X1040496Y-39319D01*
X1038968Y-39028D01*
X1037440Y-39611D01*
X1036130Y-40777D01*
X1035256Y-42527D01*
X1034820Y-44861D01*
X1035256Y-47194D01*
X1036130Y-48944D01*
X1037440Y-50111D01*
X1038968Y-50694D01*
X1040496Y-50402D01*
X1041807Y-49528D01*
X1042680Y-48361D01*
G01X1052538Y-50694D02*
Y-39028D01*
G01Y-41944D02*
X1053412Y-40486D01*
X1054722Y-39319D01*
X1056468Y-39028D01*
X1057996Y-39319D01*
X1059307Y-40486D01*
X1059962Y-42527D01*
Y-50694D01*
G01X1077243Y-40486D02*
X1075715Y-39319D01*
X1074405Y-39028D01*
X1072658Y-39611D01*
X1071348Y-40777D01*
X1070475Y-42819D01*
X1070256Y-44861D01*
X1070475Y-46903D01*
X1071348Y-48653D01*
X1072658Y-50111D01*
X1074405Y-50694D01*
X1075933Y-50111D01*
X1077243Y-48944D01*
G01X1087975Y-42819D02*
X1094962D01*
X1094307Y-40777D01*
X1093215Y-39611D01*
X1091687Y-39028D01*
X1090158Y-39319D01*
X1088848Y-40194D01*
X1087975Y-42236D01*
X1087538Y-43986D01*
Y-45736D01*
X1087975Y-47486D01*
X1089067Y-49236D01*
X1090377Y-50402D01*
X1091905Y-50694D01*
X1093433Y-50111D01*
X1094962Y-48361D01*
G01X1126250Y-33194D02*
Y-50694D01*
G01X1123193Y-39028D02*
X1129307D01*
G01X1140693Y-50694D02*
Y-39028D01*
G01Y-41361D02*
X1141785Y-40194D01*
X1142877Y-39319D01*
X1144405Y-39028D01*
X1145496Y-39319D01*
X1146807Y-40194D01*
G01X1165180Y-50694D02*
Y-39028D01*
G01Y-41069D02*
X1164307Y-39903D01*
X1162996Y-39319D01*
X1161468Y-39028D01*
X1159940Y-39611D01*
X1158630Y-40777D01*
X1157756Y-42527D01*
X1157320Y-44861D01*
X1157756Y-47194D01*
X1158630Y-48944D01*
X1159940Y-50111D01*
X1161468Y-50694D01*
X1162996Y-50402D01*
X1164307Y-49528D01*
X1165180Y-48361D01*
G01X1182243Y-40486D02*
X1180715Y-39319D01*
X1179405Y-39028D01*
X1177658Y-39611D01*
X1176348Y-40777D01*
X1175475Y-42819D01*
X1175256Y-44861D01*
X1175475Y-46903D01*
X1176348Y-48653D01*
X1177658Y-50111D01*
X1179405Y-50694D01*
X1180933Y-50111D01*
X1182243Y-48944D01*
G01X1192975Y-42819D02*
X1199962D01*
X1199307Y-40777D01*
X1198215Y-39611D01*
X1196687Y-39028D01*
X1195158Y-39319D01*
X1193848Y-40194D01*
X1192975Y-42236D01*
X1192538Y-43986D01*
Y-45736D01*
X1192975Y-47486D01*
X1194067Y-49236D01*
X1195377Y-50402D01*
X1196905Y-50694D01*
X1198433Y-50111D01*
X1199962Y-48361D01*
G01X1210475Y-48653D02*
X1211567Y-49819D01*
X1213095Y-50694D01*
X1214405D01*
X1215715Y-50111D01*
X1216588Y-49236D01*
X1217025Y-48070D01*
X1216807Y-46319D01*
X1215933Y-45444D01*
X1212003Y-43694D01*
X1211130Y-41652D01*
X1211567Y-40194D01*
X1212440Y-39319D01*
X1213750Y-39028D01*
X1215060Y-39319D01*
X1216370Y-40194D01*
G01X1248750Y-39028D02*
Y-50694D01*
G01Y-34361D02*
X1248313Y-34069D01*
Y-33486D01*
X1248750Y-33194D01*
X1249187Y-33486D01*
Y-34069D01*
X1248750Y-34361D01*
G01X1262538Y-50694D02*
Y-39028D01*
G01Y-41944D02*
X1263412Y-40486D01*
X1264722Y-39319D01*
X1266468Y-39028D01*
X1267996Y-39319D01*
X1269307Y-40486D01*
X1269962Y-42527D01*
Y-50694D01*
G01X1301250D02*
Y-33194D01*
G01X1322680Y-50694D02*
Y-39028D01*
G01Y-41069D02*
X1321807Y-39903D01*
X1320496Y-39319D01*
X1318968Y-39028D01*
X1317440Y-39611D01*
X1316130Y-40777D01*
X1315256Y-42527D01*
X1314820Y-44861D01*
X1315256Y-47194D01*
X1316130Y-48944D01*
X1317440Y-50111D01*
X1318968Y-50694D01*
X1320496Y-50402D01*
X1321807Y-49528D01*
X1322680Y-48361D01*
G01X1331665Y-55944D02*
X1332975Y-56527D01*
X1334722Y-55944D01*
X1335813Y-54778D01*
X1336687Y-53319D01*
X1337996Y-48653D01*
X1340835Y-39028D01*
G01X1333848D02*
X1337996Y-48653D01*
G01X1350475Y-42819D02*
X1357462D01*
X1356807Y-40777D01*
X1355715Y-39611D01*
X1354187Y-39028D01*
X1352658Y-39319D01*
X1351348Y-40194D01*
X1350475Y-42236D01*
X1350038Y-43986D01*
Y-45736D01*
X1350475Y-47486D01*
X1351567Y-49236D01*
X1352877Y-50402D01*
X1354405Y-50694D01*
X1355933Y-50111D01*
X1357462Y-48361D01*
G01X1368193Y-50694D02*
Y-39028D01*
G01Y-41361D02*
X1369285Y-40194D01*
X1370377Y-39319D01*
X1371905Y-39028D01*
X1372996Y-39319D01*
X1374307Y-40194D01*
G01X1401883Y-33194D02*
Y-50694D01*
X1410617D01*
G01X1419602Y-43403D02*
X1421130Y-41361D01*
X1422440Y-40194D01*
X1424187Y-39611D01*
X1425715Y-40194D01*
X1426807Y-41361D01*
X1427680Y-43111D01*
X1427898Y-45152D01*
X1427680Y-46903D01*
X1426807Y-48653D01*
X1425496Y-50111D01*
X1423968Y-50694D01*
X1422222Y-50111D01*
X1420693Y-48361D01*
X1419820Y-45736D01*
X1419602Y-42819D01*
X1420038Y-39028D01*
X1420693Y-36985D01*
X1421785Y-34944D01*
X1423313Y-33486D01*
X1424842Y-33194D01*
X1426370Y-33777D01*
X1427462Y-35236D01*
G01X1441250Y-51277D02*
X1440813Y-50986D01*
Y-50402D01*
X1441250Y-50111D01*
X1441687Y-50402D01*
Y-50986D01*
X1441250Y-51277D01*
G01X1987108Y1497418D02*
X1988855Y1495960D01*
X1990820Y1495085D01*
X1992566D01*
X1994313Y1495960D01*
X1995623Y1497418D01*
X1996278Y1499460D01*
X1995841Y1501501D01*
X1994750Y1503252D01*
X1992785Y1504418D01*
X1990165Y1505002D01*
X1988636Y1506168D01*
X1987981Y1508210D01*
X1988418Y1510252D01*
X1989510Y1511710D01*
X1991038Y1512585D01*
X1992566D01*
X1994095Y1512002D01*
X1995405Y1510543D01*
G01X2013560Y1495085D02*
X2004826D01*
Y1512585D01*
X2013560D01*
G01X2010066Y1504127D02*
X2004826D01*
G01X2041573Y1512585D02*
X2046813D01*
G01X2044193D02*
Y1495085D01*
G01X2041573D02*
X2046813D01*
G01X2056016D02*
Y1512585D01*
X2061693Y1498002D01*
X2067370Y1512585D01*
Y1495085D01*
G01X2074826D02*
Y1512585D01*
X2080066D01*
X2081813Y1511710D01*
X2083123Y1509668D01*
X2083560Y1507335D01*
X2083123Y1505002D01*
X2082031Y1503252D01*
X2080066Y1502376D01*
X2074826D01*
G01X2101060Y1495085D02*
X2092326D01*
Y1512585D01*
X2101060D01*
G01X2097566Y1504127D02*
X2092326D01*
G01X2109390Y1495085D02*
Y1512585D01*
X2113756D01*
X2115503Y1511710D01*
X2116813Y1510543D01*
X2117905Y1508794D01*
X2118778Y1506751D01*
X2118996Y1503835D01*
X2118778Y1500918D01*
X2117905Y1498876D01*
X2116813Y1497126D01*
X2115503Y1495960D01*
X2113756Y1495085D01*
X2109390D01*
G01X2126234D02*
X2131693Y1512585D01*
X2137152Y1495085D01*
G01X2135186Y1501210D02*
X2128199D01*
G01X2144171Y1495085D02*
Y1512585D01*
X2154215Y1495085D01*
Y1512585D01*
G01X2171496Y1511126D02*
X2170186Y1512002D01*
X2168658Y1512585D01*
X2166911D01*
X2164946Y1511710D01*
X2163418Y1510252D01*
X2162326Y1508501D01*
X2161453Y1505585D01*
X2161234Y1502960D01*
X2161671Y1500335D01*
X2162326Y1498585D01*
X2163636Y1496835D01*
X2165165Y1495668D01*
X2166693Y1495085D01*
X2168221D01*
X2169750Y1495668D01*
X2171060Y1496543D01*
X2172152Y1497709D01*
G01X2188560Y1495085D02*
X2179826D01*
Y1512585D01*
X2188560D01*
G01X2185066Y1504127D02*
X2179826D01*
G01X2219193Y1512585D02*
Y1495085D01*
G01X2214171Y1512585D02*
X2224215D01*
G01X2231234Y1495085D02*
X2236693Y1512585D01*
X2242152Y1495085D01*
G01X2240186Y1501210D02*
X2233199D01*
G01X2255939Y1504418D02*
X2256813Y1505293D01*
X2257468Y1506751D01*
X2257905Y1508794D01*
X2257468Y1510543D01*
X2256595Y1511710D01*
X2255066Y1512585D01*
X2249171D01*
Y1495085D01*
X2256376D01*
X2257905Y1496251D01*
X2258778Y1498002D01*
X2259215Y1500043D01*
X2258778Y1502085D01*
X2257468Y1503835D01*
X2255939Y1504418D01*
X2249171D01*
G01X2267326Y1512585D02*
Y1495085D01*
X2276060D01*
G01X2293560D02*
X2284826D01*
Y1512585D01*
X2293560D01*
G01X2290066Y1504127D02*
X2284826D01*
G01X2306693Y1494502D02*
X2306256Y1494793D01*
Y1495377D01*
X2306693Y1495668D01*
X2307130Y1495377D01*
Y1494793D01*
X2306693Y1494502D01*
G01Y1502376D02*
X2306256Y1502668D01*
Y1503252D01*
X2306693Y1503543D01*
X2307130Y1503252D01*
Y1502668D01*
X2306693Y1502376D01*
G01X2337326Y1512585D02*
Y1495085D01*
X2346060D01*
G01X2355045Y1502376D02*
X2356573Y1504418D01*
X2357883Y1505585D01*
X2359630Y1506168D01*
X2361158Y1505585D01*
X2362250Y1504418D01*
X2363123Y1502668D01*
X2363341Y1500627D01*
X2363123Y1498876D01*
X2362250Y1497126D01*
X2360939Y1495668D01*
X2359411Y1495085D01*
X2357665Y1495668D01*
X2356136Y1497418D01*
X2355263Y1500043D01*
X2355045Y1502960D01*
X2355481Y1506751D01*
X2356136Y1508794D01*
X2357228Y1510835D01*
X2358756Y1512293D01*
X2360285Y1512585D01*
X2361813Y1512002D01*
X2362905Y1510543D01*
G01X2008773Y1477935D02*
X2014013D01*
G01X2011393D02*
Y1460435D01*
G01X2008773D02*
X2014013D01*
G01X2023216D02*
Y1477935D01*
X2028893Y1463352D01*
X2034570Y1477935D01*
Y1460435D01*
G01X2042026D02*
Y1477935D01*
X2047266D01*
X2049013Y1477060D01*
X2050323Y1475018D01*
X2050760Y1472685D01*
X2050323Y1470352D01*
X2049231Y1468602D01*
X2047266Y1467726D01*
X2042026D01*
G01X2062801Y1454602D02*
X2060618Y1457518D01*
X2059526Y1460435D01*
Y1472101D01*
X2060618Y1475018D01*
X2062801Y1477935D01*
G01X2081393Y1460435D02*
X2079646Y1460727D01*
X2078118Y1461893D01*
X2076808Y1463643D01*
X2075934Y1465685D01*
X2075498Y1468018D01*
Y1470352D01*
X2075934Y1472685D01*
X2076808Y1474727D01*
X2078118Y1476476D01*
X2079646Y1477643D01*
X2081393Y1477935D01*
X2083139Y1477643D01*
X2084668Y1476476D01*
X2085978Y1474727D01*
X2086852Y1472685D01*
X2087288Y1470352D01*
Y1468018D01*
X2086852Y1465685D01*
X2085978Y1463643D01*
X2084668Y1461893D01*
X2083139Y1460727D01*
X2081393Y1460435D01*
G01X2095181D02*
Y1477935D01*
G01Y1469477D02*
X2096273Y1470935D01*
X2097365Y1471810D01*
X2099111Y1472101D01*
X2100421Y1471810D01*
X2101950Y1470643D01*
X2102605Y1468893D01*
Y1460435D01*
G01X2109843D02*
Y1472101D01*
G01Y1468893D02*
X2110498Y1470352D01*
X2111590Y1471518D01*
X2113118Y1472101D01*
X2114646Y1471518D01*
X2115738Y1470352D01*
X2116393Y1468893D01*
Y1460435D01*
G01Y1468893D02*
X2117048Y1470352D01*
X2118139Y1471518D01*
X2119668Y1472101D01*
X2121196Y1471518D01*
X2122288Y1470352D01*
X2122943Y1468602D01*
Y1460435D01*
G01X2134985Y1454602D02*
X2137168Y1457518D01*
X2138260Y1460435D01*
Y1472101D01*
X2137168Y1475018D01*
X2134985Y1477935D01*
G01X2041590Y1428409D02*
X2042899Y1426951D01*
X2044428Y1426077D01*
X2046393Y1425785D01*
X2048358Y1426368D01*
X2049886Y1427535D01*
X2050978Y1429576D01*
X2051196Y1431910D01*
X2050760Y1434243D01*
X2049668Y1435702D01*
X2048139Y1436868D01*
X2046611Y1437160D01*
X2045083Y1436868D01*
X2043118Y1435702D01*
X2043773Y1443285D01*
X2049668D01*
G01X2063893D02*
X2062146Y1442702D01*
X2060836Y1441243D01*
X2059963Y1439494D01*
X2059308Y1437160D01*
X2059090Y1434535D01*
X2059308Y1431910D01*
X2059963Y1429576D01*
X2060836Y1427826D01*
X2062146Y1426368D01*
X2063893Y1425785D01*
X2065639Y1426368D01*
X2066950Y1427826D01*
X2067823Y1429576D01*
X2068478Y1431910D01*
X2068696Y1434535D01*
X2068478Y1437160D01*
X2067823Y1439494D01*
X2066950Y1441243D01*
X2065639Y1442702D01*
X2063893Y1443285D01*
G01X2081393Y1425202D02*
X2080956Y1425493D01*
Y1426077D01*
X2081393Y1426368D01*
X2081830Y1426077D01*
Y1425493D01*
X2081393Y1425202D01*
G01X2098893Y1443285D02*
X2097146Y1442702D01*
X2095836Y1441243D01*
X2094963Y1439494D01*
X2094308Y1437160D01*
X2094090Y1434535D01*
X2094308Y1431910D01*
X2094963Y1429576D01*
X2095836Y1427826D01*
X2097146Y1426368D01*
X2098893Y1425785D01*
X2100639Y1426368D01*
X2101950Y1427826D01*
X2102823Y1429576D01*
X2103478Y1431910D01*
X2103696Y1434535D01*
X2103478Y1437160D01*
X2102823Y1439494D01*
X2101950Y1441243D01*
X2100639Y1442702D01*
X2098893Y1443285D01*
G01X2188593Y1477935D02*
X2191649Y1460435D01*
X2195143Y1477935D01*
X2198636Y1460435D01*
X2201693Y1477935D01*
G01X2210023D02*
X2215263D01*
G01X2212643D02*
Y1460435D01*
G01X2210023D02*
X2215263D01*
G01X2225340D02*
Y1477935D01*
X2229706D01*
X2231453Y1477060D01*
X2232763Y1475893D01*
X2233855Y1474144D01*
X2234728Y1472101D01*
X2234946Y1469185D01*
X2234728Y1466268D01*
X2233855Y1464226D01*
X2232763Y1462476D01*
X2231453Y1461310D01*
X2229706Y1460435D01*
X2225340D01*
G01X2247643Y1477935D02*
Y1460435D01*
G01X2242621Y1477935D02*
X2252665D01*
G01X2260558Y1460435D02*
Y1477935D01*
G01X2269728D02*
Y1460435D01*
G01Y1469185D02*
X2260558D01*
G01X2281551Y1454602D02*
X2279368Y1457518D01*
X2278276Y1460435D01*
Y1472101D01*
X2279368Y1475018D01*
X2281551Y1477935D01*
G01X2293593Y1460435D02*
Y1472101D01*
G01Y1468893D02*
X2294248Y1470352D01*
X2295340Y1471518D01*
X2296868Y1472101D01*
X2298396Y1471518D01*
X2299488Y1470352D01*
X2300143Y1468893D01*
Y1460435D01*
G01Y1468893D02*
X2300798Y1470352D01*
X2301889Y1471518D01*
X2303418Y1472101D01*
X2304946Y1471518D01*
X2306038Y1470352D01*
X2306693Y1468602D01*
Y1460435D01*
G01X2317643Y1472101D02*
Y1460435D01*
G01Y1476768D02*
X2317206Y1477060D01*
Y1477643D01*
X2317643Y1477935D01*
X2318080Y1477643D01*
Y1477060D01*
X2317643Y1476768D01*
G01X2335143Y1460435D02*
Y1477935D01*
G01X2349368Y1462476D02*
X2350460Y1461310D01*
X2351988Y1460435D01*
X2353298D01*
X2354608Y1461018D01*
X2355481Y1461893D01*
X2355918Y1463059D01*
X2355700Y1464810D01*
X2354826Y1465685D01*
X2350896Y1467435D01*
X2350023Y1469477D01*
X2350460Y1470935D01*
X2351333Y1471810D01*
X2352643Y1472101D01*
X2353953Y1471810D01*
X2355263Y1470935D01*
G01X2371235Y1454602D02*
X2373418Y1457518D01*
X2374510Y1460435D01*
Y1472101D01*
X2373418Y1475018D01*
X2371235Y1477935D01*
G01X2251590Y1428409D02*
X2252899Y1426951D01*
X2254428Y1426077D01*
X2256393Y1425785D01*
X2258358Y1426368D01*
X2259886Y1427535D01*
X2260978Y1429576D01*
X2261196Y1431910D01*
X2260760Y1434243D01*
X2259668Y1435702D01*
X2258139Y1436868D01*
X2256611Y1437160D01*
X2255083Y1436868D01*
X2253118Y1435702D01*
X2253773Y1443285D01*
X2259668D01*
G01X2273893Y1425202D02*
X2273456Y1425493D01*
Y1426077D01*
X2273893Y1426368D01*
X2274330Y1426077D01*
Y1425493D01*
X2273893Y1425202D01*
G01X2290956Y1425785D02*
X2291393Y1429576D01*
X2292048Y1432785D01*
X2292921Y1435702D01*
X2294013Y1438910D01*
X2295760Y1443285D01*
X2287026D01*
G01X2304090Y1428409D02*
X2305399Y1426951D01*
X2306928Y1426077D01*
X2308893Y1425785D01*
X2310858Y1426368D01*
X2312386Y1427535D01*
X2313478Y1429576D01*
X2313696Y1431910D01*
X2313260Y1434243D01*
X2312168Y1435702D01*
X2310639Y1436868D01*
X2309111Y1437160D01*
X2307583Y1436868D01*
X2305618Y1435702D01*
X2306273Y1443285D01*
X2312168D01*
G01X2444308Y1428118D02*
X2446055Y1426660D01*
X2448020Y1425785D01*
X2449766D01*
X2451513Y1426660D01*
X2452823Y1428118D01*
X2453478Y1430160D01*
X2453041Y1432201D01*
X2451950Y1433952D01*
X2449985Y1435118D01*
X2447365Y1435702D01*
X2445836Y1436868D01*
X2445181Y1438910D01*
X2445618Y1440952D01*
X2446710Y1442410D01*
X2448238Y1443285D01*
X2449766D01*
X2451295Y1442702D01*
X2452605Y1441243D01*
G01X2470760Y1425785D02*
X2462026D01*
Y1443285D01*
X2470760D01*
G01X2467266Y1434827D02*
X2462026D01*
G01X2431393Y1477935D02*
Y1460435D01*
G01X2426371Y1477935D02*
X2436415D01*
G01X2448893Y1460435D02*
Y1468310D01*
X2444526Y1477935D01*
G01X2453260D02*
X2448893Y1468310D01*
G01X2462026Y1460435D02*
Y1477935D01*
X2467266D01*
X2469013Y1477060D01*
X2470323Y1475018D01*
X2470760Y1472685D01*
X2470323Y1470352D01*
X2469231Y1468602D01*
X2467266Y1467726D01*
X2462026D01*
G01X2488260Y1460435D02*
X2479526D01*
Y1477935D01*
X2488260D01*
G01X2484766Y1469477D02*
X2479526D01*
G01X2575776Y1443285D02*
Y1425785D01*
X2584510D01*
G01X2592840Y1428409D02*
X2594149Y1426951D01*
X2595678Y1426077D01*
X2597643Y1425785D01*
X2599608Y1426368D01*
X2601136Y1427535D01*
X2602228Y1429576D01*
X2602446Y1431910D01*
X2602010Y1434243D01*
X2600918Y1435702D01*
X2599389Y1436868D01*
X2597861Y1437160D01*
X2596333Y1436868D01*
X2594368Y1435702D01*
X2595023Y1443285D01*
X2600918D01*
G01X2611213Y1425202D02*
X2619073Y1443285D01*
G01X2628276D02*
Y1425785D01*
X2637010D01*
G01X2649706D02*
X2650143Y1429576D01*
X2650798Y1432785D01*
X2651671Y1435702D01*
X2652763Y1438910D01*
X2654510Y1443285D01*
X2645776D01*
G01X2532026Y1460435D02*
Y1477935D01*
X2537485D01*
X2539231Y1477060D01*
X2540323Y1475893D01*
X2540760Y1473560D01*
X2540323Y1471226D01*
X2539013Y1469768D01*
X2537485Y1468893D01*
X2532026D01*
G01X2537485D02*
X2540760Y1460435D01*
G01X2550618Y1468310D02*
X2557605D01*
X2556950Y1470352D01*
X2555858Y1471518D01*
X2554330Y1472101D01*
X2552801Y1471810D01*
X2551491Y1470935D01*
X2550618Y1468893D01*
X2550181Y1467143D01*
Y1465393D01*
X2550618Y1463643D01*
X2551710Y1461893D01*
X2553020Y1460727D01*
X2554548Y1460435D01*
X2556076Y1461018D01*
X2557605Y1462768D01*
G01X2570083Y1460435D02*
Y1475310D01*
X2570520Y1476768D01*
X2571393Y1477643D01*
X2572703Y1477935D01*
X2574013Y1477352D01*
X2574668Y1475893D01*
G01X2572048Y1470935D02*
X2567681D01*
G01X2588893Y1459852D02*
X2588456Y1460143D01*
Y1460727D01*
X2588893Y1461018D01*
X2589330Y1460727D01*
Y1460143D01*
X2588893Y1459852D01*
G01X2619526Y1460435D02*
Y1477935D01*
X2624766D01*
X2626513Y1477060D01*
X2627823Y1475018D01*
X2628260Y1472685D01*
X2627823Y1470352D01*
X2626731Y1468602D01*
X2624766Y1467726D01*
X2619526D01*
G01X2641393Y1460435D02*
Y1477935D01*
G01X2662823Y1460435D02*
Y1472101D01*
G01Y1470060D02*
X2661950Y1471226D01*
X2660639Y1471810D01*
X2659111Y1472101D01*
X2657583Y1471518D01*
X2656273Y1470352D01*
X2655399Y1468602D01*
X2654963Y1466268D01*
X2655399Y1463935D01*
X2656273Y1462185D01*
X2657583Y1461018D01*
X2659111Y1460435D01*
X2660639Y1460727D01*
X2661950Y1461601D01*
X2662823Y1462768D01*
G01X2672681Y1460435D02*
Y1472101D01*
G01Y1469185D02*
X2673555Y1470643D01*
X2674865Y1471810D01*
X2676611Y1472101D01*
X2678139Y1471810D01*
X2679450Y1470643D01*
X2680105Y1468602D01*
Y1460435D01*
G01X2690618Y1468310D02*
X2697605D01*
X2696950Y1470352D01*
X2695858Y1471518D01*
X2694330Y1472101D01*
X2692801Y1471810D01*
X2691491Y1470935D01*
X2690618Y1468893D01*
X2690181Y1467143D01*
Y1465393D01*
X2690618Y1463643D01*
X2691710Y1461893D01*
X2693020Y1460727D01*
X2694548Y1460435D01*
X2696076Y1461018D01*
X2697605Y1462768D01*
G01X2811693Y1437451D02*
Y1425785D01*
G01Y1442118D02*
X2811256Y1442410D01*
Y1442993D01*
X2811693Y1443285D01*
X2812130Y1442993D01*
Y1442410D01*
X2811693Y1442118D01*
G01X2825918Y1427826D02*
X2827010Y1426660D01*
X2828538Y1425785D01*
X2829848D01*
X2831158Y1426368D01*
X2832031Y1427243D01*
X2832468Y1428409D01*
X2832250Y1430160D01*
X2831376Y1431035D01*
X2827446Y1432785D01*
X2826573Y1434827D01*
X2827010Y1436285D01*
X2827883Y1437160D01*
X2829193Y1437451D01*
X2830503Y1437160D01*
X2831813Y1436285D01*
G01X2859171Y1425785D02*
Y1443285D01*
X2869215Y1425785D01*
Y1443285D01*
G01X2881693Y1425785D02*
X2879946Y1426077D01*
X2878418Y1427243D01*
X2877108Y1428993D01*
X2876234Y1431035D01*
X2875798Y1433368D01*
Y1435702D01*
X2876234Y1438035D01*
X2877108Y1440077D01*
X2878418Y1441826D01*
X2879946Y1442993D01*
X2881693Y1443285D01*
X2883439Y1442993D01*
X2884968Y1441826D01*
X2886278Y1440077D01*
X2887152Y1438035D01*
X2887588Y1435702D01*
Y1433368D01*
X2887152Y1431035D01*
X2886278Y1428993D01*
X2884968Y1427243D01*
X2883439Y1426077D01*
X2881693Y1425785D01*
G01X2899193Y1443285D02*
Y1425785D01*
G01X2894171Y1443285D02*
X2904215D01*
G01X2930481Y1437451D02*
Y1429285D01*
X2931355Y1427243D01*
X2932665Y1426077D01*
X2934193Y1425785D01*
X2935721Y1426077D01*
X2937031Y1427243D01*
X2937905Y1429285D01*
G01Y1425785D02*
Y1437451D01*
G01X2948418Y1427826D02*
X2949510Y1426660D01*
X2951038Y1425785D01*
X2952348D01*
X2953658Y1426368D01*
X2954531Y1427243D01*
X2954968Y1428409D01*
X2954750Y1430160D01*
X2953876Y1431035D01*
X2949946Y1432785D01*
X2949073Y1434827D01*
X2949510Y1436285D01*
X2950383Y1437160D01*
X2951693Y1437451D01*
X2953003Y1437160D01*
X2954313Y1436285D01*
G01X2965918Y1433660D02*
X2972905D01*
X2972250Y1435702D01*
X2971158Y1436868D01*
X2969630Y1437451D01*
X2968101Y1437160D01*
X2966791Y1436285D01*
X2965918Y1434243D01*
X2965481Y1432493D01*
Y1430743D01*
X2965918Y1428993D01*
X2967010Y1427243D01*
X2968320Y1426077D01*
X2969848Y1425785D01*
X2971376Y1426368D01*
X2972905Y1428118D01*
G01X2990623Y1443285D02*
Y1425785D01*
G01Y1428409D02*
X2989750Y1426951D01*
X2988439Y1426077D01*
X2986911Y1425785D01*
X2985165Y1426368D01*
X2983855Y1427826D01*
X2982981Y1429576D01*
X2982763Y1431618D01*
X2982981Y1433660D01*
X2983855Y1435410D01*
X2985165Y1436868D01*
X2986911Y1437451D01*
X2988439Y1437160D01*
X2989531Y1436576D01*
X2990623Y1435410D01*
G01X2736890Y1459852D02*
X2746496Y1472685D01*
G01X2741693Y1475018D02*
Y1457518D01*
G01X2746496Y1459852D02*
X2736890Y1472685D01*
G01X2735143Y1466268D02*
X2748243D01*
G01X2773855D02*
X2779531D01*
G01X2806890Y1460435D02*
Y1477935D01*
X2811256D01*
X2813003Y1477060D01*
X2814313Y1475893D01*
X2815405Y1474144D01*
X2816278Y1472101D01*
X2816496Y1469185D01*
X2816278Y1466268D01*
X2815405Y1464226D01*
X2814313Y1462476D01*
X2813003Y1461310D01*
X2811256Y1460435D01*
X2806890D01*
G01X2825918Y1468310D02*
X2832905D01*
X2832250Y1470352D01*
X2831158Y1471518D01*
X2829630Y1472101D01*
X2828101Y1471810D01*
X2826791Y1470935D01*
X2825918Y1468893D01*
X2825481Y1467143D01*
Y1465393D01*
X2825918Y1463643D01*
X2827010Y1461893D01*
X2828320Y1460727D01*
X2829848Y1460435D01*
X2831376Y1461018D01*
X2832905Y1462768D01*
G01X2842981Y1460435D02*
Y1472101D01*
G01Y1469185D02*
X2843855Y1470643D01*
X2845165Y1471810D01*
X2846911Y1472101D01*
X2848439Y1471810D01*
X2849750Y1470643D01*
X2850405Y1468602D01*
Y1460435D01*
G01X2864193D02*
X2862883Y1460727D01*
X2861573Y1461893D01*
X2860699Y1463935D01*
X2860263Y1466268D01*
X2860699Y1468602D01*
X2861573Y1470643D01*
X2862883Y1471810D01*
X2864193Y1472101D01*
X2865503Y1471810D01*
X2866813Y1470643D01*
X2867686Y1468602D01*
X2867905Y1466268D01*
X2867686Y1463935D01*
X2866813Y1461893D01*
X2865503Y1460727D01*
X2864193Y1460435D01*
G01X2881693Y1477935D02*
Y1460435D01*
G01X2878636Y1472101D02*
X2884750D01*
G01X2895918Y1468310D02*
X2902905D01*
X2902250Y1470352D01*
X2901158Y1471518D01*
X2899630Y1472101D01*
X2898101Y1471810D01*
X2896791Y1470935D01*
X2895918Y1468893D01*
X2895481Y1467143D01*
Y1465393D01*
X2895918Y1463643D01*
X2897010Y1461893D01*
X2898320Y1460727D01*
X2899848Y1460435D01*
X2901376Y1461018D01*
X2902905Y1462768D01*
G01X2913418Y1462476D02*
X2914510Y1461310D01*
X2916038Y1460435D01*
X2917348D01*
X2918658Y1461018D01*
X2919531Y1461893D01*
X2919968Y1463059D01*
X2919750Y1464810D01*
X2918876Y1465685D01*
X2914946Y1467435D01*
X2914073Y1469477D01*
X2914510Y1470935D01*
X2915383Y1471810D01*
X2916693Y1472101D01*
X2918003Y1471810D01*
X2919313Y1470935D01*
G01X2951693Y1477935D02*
Y1460435D01*
G01X2948636Y1472101D02*
X2954750D01*
G01X2965481Y1460435D02*
Y1477935D01*
G01Y1469477D02*
X2966573Y1470935D01*
X2967665Y1471810D01*
X2969411Y1472101D01*
X2970721Y1471810D01*
X2972250Y1470643D01*
X2972905Y1468893D01*
Y1460435D01*
G01X2990623D02*
Y1472101D01*
G01Y1470060D02*
X2989750Y1471226D01*
X2988439Y1471810D01*
X2986911Y1472101D01*
X2985383Y1471518D01*
X2984073Y1470352D01*
X2983199Y1468602D01*
X2982763Y1466268D01*
X2983199Y1463935D01*
X2984073Y1462185D01*
X2985383Y1461018D01*
X2986911Y1460435D01*
X2988439Y1460727D01*
X2989750Y1461601D01*
X2990623Y1462768D01*
G01X3004193Y1477935D02*
Y1460435D01*
G01X3001136Y1472101D02*
X3007250D01*
G01X3039193Y1477935D02*
Y1460435D01*
G01X3036136Y1472101D02*
X3042250D01*
G01X3052981Y1460435D02*
Y1477935D01*
G01Y1469477D02*
X3054073Y1470935D01*
X3055165Y1471810D01*
X3056911Y1472101D01*
X3058221Y1471810D01*
X3059750Y1470643D01*
X3060405Y1468893D01*
Y1460435D01*
G01X3074193Y1472101D02*
Y1460435D01*
G01Y1476768D02*
X3073756Y1477060D01*
Y1477643D01*
X3074193Y1477935D01*
X3074630Y1477643D01*
Y1477060D01*
X3074193Y1476768D01*
G01X3088418Y1462476D02*
X3089510Y1461310D01*
X3091038Y1460435D01*
X3092348D01*
X3093658Y1461018D01*
X3094531Y1461893D01*
X3094968Y1463059D01*
X3094750Y1464810D01*
X3093876Y1465685D01*
X3089946Y1467435D01*
X3089073Y1469477D01*
X3089510Y1470935D01*
X3090383Y1471810D01*
X3091693Y1472101D01*
X3093003Y1471810D01*
X3094313Y1470935D01*
G01X3124073Y1477935D02*
X3129313D01*
G01X3126693D02*
Y1460435D01*
G01X3124073D02*
X3129313D01*
G01X3137643D02*
Y1472101D01*
G01Y1468893D02*
X3138298Y1470352D01*
X3139390Y1471518D01*
X3140918Y1472101D01*
X3142446Y1471518D01*
X3143538Y1470352D01*
X3144193Y1468893D01*
Y1460435D01*
G01Y1468893D02*
X3144848Y1470352D01*
X3145939Y1471518D01*
X3147468Y1472101D01*
X3148996Y1471518D01*
X3150088Y1470352D01*
X3150743Y1468602D01*
Y1460435D01*
G01X3157763Y1454602D02*
Y1472101D01*
G01Y1469477D02*
X3158855Y1470935D01*
X3159946Y1471810D01*
X3161693Y1472101D01*
X3163221Y1471810D01*
X3164750Y1470352D01*
X3165405Y1468310D01*
X3165623Y1466268D01*
X3165405Y1464226D01*
X3164750Y1462185D01*
X3163439Y1461018D01*
X3161693Y1460435D01*
X3160165Y1460727D01*
X3158636Y1461601D01*
X3157763Y1462768D01*
G01X3175918Y1468310D02*
X3182905D01*
X3182250Y1470352D01*
X3181158Y1471518D01*
X3179630Y1472101D01*
X3178101Y1471810D01*
X3176791Y1470935D01*
X3175918Y1468893D01*
X3175481Y1467143D01*
Y1465393D01*
X3175918Y1463643D01*
X3177010Y1461893D01*
X3178320Y1460727D01*
X3179848Y1460435D01*
X3181376Y1461018D01*
X3182905Y1462768D01*
G01X3200623Y1477935D02*
Y1460435D01*
G01Y1463059D02*
X3199750Y1461601D01*
X3198439Y1460727D01*
X3196911Y1460435D01*
X3195165Y1461018D01*
X3193855Y1462476D01*
X3192981Y1464226D01*
X3192763Y1466268D01*
X3192981Y1468310D01*
X3193855Y1470060D01*
X3195165Y1471518D01*
X3196911Y1472101D01*
X3198439Y1471810D01*
X3199531Y1471226D01*
X3200623Y1470060D01*
G01X3218123Y1460435D02*
Y1472101D01*
G01Y1470060D02*
X3217250Y1471226D01*
X3215939Y1471810D01*
X3214411Y1472101D01*
X3212883Y1471518D01*
X3211573Y1470352D01*
X3210699Y1468602D01*
X3210263Y1466268D01*
X3210699Y1463935D01*
X3211573Y1462185D01*
X3212883Y1461018D01*
X3214411Y1460435D01*
X3215939Y1460727D01*
X3217250Y1461601D01*
X3218123Y1462768D01*
G01X3227981Y1460435D02*
Y1472101D01*
G01Y1469185D02*
X3228855Y1470643D01*
X3230165Y1471810D01*
X3231911Y1472101D01*
X3233439Y1471810D01*
X3234750Y1470643D01*
X3235405Y1468602D01*
Y1460435D01*
G01X3252686Y1470643D02*
X3251158Y1471810D01*
X3249848Y1472101D01*
X3248101Y1471518D01*
X3246791Y1470352D01*
X3245918Y1468310D01*
X3245699Y1466268D01*
X3245918Y1464226D01*
X3246791Y1462476D01*
X3248101Y1461018D01*
X3249848Y1460435D01*
X3251376Y1461018D01*
X3252686Y1462185D01*
G01X3263418Y1468310D02*
X3270405D01*
X3269750Y1470352D01*
X3268658Y1471518D01*
X3267130Y1472101D01*
X3265601Y1471810D01*
X3264291Y1470935D01*
X3263418Y1468893D01*
X3262981Y1467143D01*
Y1465393D01*
X3263418Y1463643D01*
X3264510Y1461893D01*
X3265820Y1460727D01*
X3267348Y1460435D01*
X3268876Y1461018D01*
X3270405Y1462768D01*
G01X0Y3937D02*
G03X3937Y0I3937J0D01*
G01X0Y3937D02*
G03X3937Y0I3937J0D01*
G01D02*
X779528D01*
G01X3937D02*
X779528D01*
G01X0Y1456693D02*
Y3937D01*
G01Y1456693D02*
Y3937D01*
G01X7874Y1460630D02*
X3937D01*
G01D02*
X7874D01*
G01X3937D02*
G03X0Y1456693I0J-3937D01*
G01X3937Y1460630D02*
G03X0Y1456693I0J-3937D01*
G01X101378Y1519685D02*
G03X97441Y1515748I0J-3937D01*
G01X101378Y1519685D02*
G03X97441Y1515748I0J-3937D01*
G01D02*
Y1509055D01*
G01Y1515748D02*
Y1509055D01*
G01X93504Y1505118D02*
X67913D01*
G01X93504D02*
G03X97441Y1509055I0J3937D01*
G01X93504Y1505118D02*
G03X97441Y1509055I0J3937D01*
G01X67913Y1505118D02*
X93504D01*
G01X63976Y1515748D02*
G03X60039Y1519685I-3937J0D01*
G01X63976Y1515748D02*
G03X60039Y1519685I-3937J0D01*
G01X63976Y1509055D02*
Y1515748D01*
G01Y1509055D02*
G03X67913Y1505118I3937J0D01*
G01X63976Y1509055D02*
G03X67913Y1505118I3937J0D01*
G01X63976Y1515748D02*
Y1509055D01*
G01X7874Y1460630D02*
G03X11811Y1464567I0J3937D01*
G01X7874Y1460630D02*
G03X11811Y1464567I0J3937D01*
G01X15748Y1519685D02*
G03X11811Y1515748I0J-3937D01*
G01X15748Y1519685D02*
G03X11811Y1515748I0J-3937D01*
G01D02*
Y1464567D01*
G01Y1515748D02*
Y1464567D01*
G01X60039Y1519685D02*
X15748D01*
G01X60039D02*
X15748D01*
G01X141181Y277843D02*
G03X148106Y264712I37662J11471D01*
G01X141181Y277843D02*
G03X148106Y264712I37662J11471D01*
G01X141181Y277843D02*
G03X121220I-9980J-3040D01*
G01X114295Y264712D02*
G03X121220Y277843I-30737J24602D01*
G01X141181D02*
G03X121220I-9980J-3040D01*
G01X114295Y264712D02*
G03X121220Y277843I-30737J24601D01*
G01X114295Y264712D02*
G03X148106I16905J-13531D01*
G01X114295D02*
G03X148106I16905J-13531D01*
G01X141181Y730599D02*
G03X148106Y717468I37662J11471D01*
G01X141181Y730599D02*
G03X148106Y717468I37662J11471D01*
G01X141181Y730599D02*
G03X121220I-9980J-3040D01*
G01X114295Y717468D02*
G03X121220Y730599I-30737J24601D01*
G01X141181D02*
G03X121220I-9980J-3040D01*
G01X114295Y717468D02*
G03X121220Y730599I-30737J24601D01*
G01X114295Y717468D02*
G03X148106I16905J-13531D01*
G01X114295D02*
G03X148106I16905J-13531D01*
G01X114295Y1170224D02*
G03X148106I16905J-13531D01*
G01X114295D02*
G03X148106I16905J-13531D01*
G01X141181Y1183355D02*
G03X148106Y1170224I37662J11471D01*
G01X141181Y1183355D02*
G03X148106Y1170224I37662J11471D01*
G01X141181Y1183355D02*
G03X121220I-9980J-3040D01*
G01X141181D02*
G03X121220I-9980J-3040D01*
G01X114295Y1170224D02*
G03X121220Y1183355I-30737J24602D01*
G01X114295Y1170224D02*
G03X121220Y1183355I-30737J24601D01*
G01X280709Y1519685D02*
X101378D01*
G01X280709D02*
X101378D01*
G01X284646Y1515748D02*
G03X280709Y1519685I-3937J0D01*
G01X284646Y1515748D02*
G03X280709Y1519685I-3937J0D01*
G01X284646Y1500000D02*
Y1515748D01*
G01Y1500000D02*
G03X288583Y1496063I3937J0D01*
G01X493307D02*
X288583D01*
G01X284646Y1500000D02*
G03X288583Y1496063I3937J0D01*
G01X493307D02*
X288583D01*
G01X284646Y1515748D02*
Y1500000D01*
G01X389213Y277843D02*
G03X369252I-9981J-3040D01*
G01X389213D02*
G03X369252I-9981J-3040D01*
G01X362327Y264712D02*
G03X369252Y277843I-30737J24602D01*
G01X362327Y264712D02*
G03X369252Y277843I-30737J24602D01*
G01X362327Y264712D02*
G03X396138I16905J-13531D01*
G01X362327D02*
G03X396138I16905J-13531D01*
G01X389213Y730599D02*
G03X369252I-9981J-3040D01*
G01X389213D02*
G03X369252I-9981J-3040D01*
G01X362327Y717468D02*
G03X369252Y730599I-30737J24602D01*
G01X362327Y717468D02*
G03X369252Y730599I-30737J24602D01*
G01X362327Y717468D02*
G03X396138I16905J-13531D01*
G01X362327D02*
G03X396138I16905J-13531D01*
G01X362327Y1170224D02*
G03X396138I16905J-13531D01*
G01X362327D02*
G03X396138I16905J-13531D01*
G01X389213Y1183355D02*
G03X369252I-9981J-3040D01*
G01X389213D02*
G03X369252I-9981J-3040D01*
G01X362327Y1170224D02*
G03X369252Y1183355I-30737J24602D01*
G01X362327Y1170224D02*
G03X369252Y1183355I-30737J24602D01*
G01X322441Y1503937D02*
G03Y1496063I0J-3937D01*
G01X459449Y1503937D02*
X322441D01*
G01X459449D02*
X322441D01*
G01D02*
G03Y1496063I0J-3937D01*
G01X296457Y1519685D02*
G03X292520Y1515748I0J-3937D01*
G01X296457Y1519685D02*
X485433D01*
G01X296457D02*
G03X292520Y1515748I0J-3937D01*
G01X296457Y1519685D02*
X485433D01*
G01X304331Y1503937D02*
X292520D01*
G01Y1515748D02*
Y1503937D01*
G01X304331D02*
X292520D01*
G01Y1515748D02*
Y1503937D01*
G01X304331Y1496063D02*
G03Y1503937I0J3937D01*
G01Y1496063D02*
G03Y1503937I0J3937D01*
G01X389213Y277843D02*
G03X396138Y264712I37662J11471D01*
G01X389213Y277843D02*
G03X396138Y264712I37662J11470D01*
G01X389213Y730599D02*
G03X396138Y717468I37662J11471D01*
G01X389213Y730599D02*
G03X396138Y717468I37662J11470D01*
G01X389213Y1183355D02*
G03X396138Y1170224I37662J11471D01*
G01X389213Y1183355D02*
G03X396138Y1170224I37662J11470D01*
G01X477559Y1503937D02*
G03Y1496063I0J-3937D01*
G01X459449D02*
G03Y1503937I0J3937D01*
G01X489370D02*
X477559D01*
G01D02*
G03Y1496063I0J-3937D01*
G01X459449D02*
G03Y1503937I0J3937D01*
G01X489370D02*
X477559D01*
G01X489370Y1515748D02*
G03X485433Y1519685I-3937J0D01*
G01X489370Y1515748D02*
G03X485433Y1519685I-3937J0D01*
G01X501181D02*
G03X497244Y1515748I0J-3937D01*
G01X680512Y1519685D02*
X501181D01*
G01D02*
G03X497244Y1515748I0J-3937D01*
G01X680512Y1519685D02*
X501181D01*
G01X489370Y1515748D02*
Y1503937D01*
G01X493307Y1496063D02*
G03X497244Y1500000I0J3937D01*
G01Y1515748D02*
Y1500000D01*
G01X489370Y1515748D02*
Y1503937D01*
G01X493307Y1496063D02*
G03X497244Y1500000I0J3937D01*
G01Y1515748D02*
Y1500000D01*
G01X637244Y277843D02*
G03X644169Y264712I37662J11471D01*
G01X637244Y277843D02*
G03X644169Y264712I37662J11471D01*
G01X637244Y277843D02*
G03X617283I-9980J-3040D01*
G01X610358Y264712D02*
G03X617283Y277843I-30737J24602D01*
G01X637244D02*
G03X617283I-9980J-3040D01*
G01X610358Y264712D02*
G03X617283Y277843I-30737J24601D01*
G01X610358Y264712D02*
G03X644169I16906J-13531D01*
G01X610358D02*
G03X644169I16906J-13531D01*
G01X637244Y730599D02*
G03X644169Y717468I37662J11471D01*
G01X637244Y730599D02*
G03X644169Y717468I37662J11471D01*
G01X637244Y730599D02*
G03X617283I-9980J-3040D01*
G01X610358Y717468D02*
G03X617283Y730599I-30737J24601D01*
G01X637244D02*
G03X617283I-9980J-3040D01*
G01X610358Y717468D02*
G03X617283Y730599I-30737J24601D01*
G01X610358Y717468D02*
G03X644169I16906J-13531D01*
G01X610358D02*
G03X644169I16906J-13531D01*
G01X610358Y1170224D02*
G03X644169I16906J-13531D01*
G01X610358D02*
G03X644169I16906J-13531D01*
G01X637244Y1183355D02*
G03X644169Y1170224I37662J11471D01*
G01X637244Y1183355D02*
G03X644169Y1170224I37662J11471D01*
G01X637244Y1183355D02*
G03X617283I-9980J-3040D01*
G01X637244D02*
G03X617283I-9980J-3040D01*
G01X610358Y1170224D02*
G03X617283Y1183355I-30737J24602D01*
G01X610358Y1170224D02*
G03X617283Y1183355I-30737J24601D01*
G01X730339Y383610D02*
G03X764149I16905J-13531D01*
G01X730339Y383609D02*
G03X764150I16905J-13530D01*
G01X757225Y396741D02*
G03X764149Y383610I37663J11469D01*
G01X757224Y396741D02*
G03X764150Y383609I37662J11471D01*
G01X757225Y396741D02*
G03X737264I-9981J-3040D01*
G01X730339Y383610D02*
G03X737264Y396741I-30737J24602D01*
G01X757224D02*
G03X737264I-9980J-3041D01*
G01X730339Y383609D02*
G03X737264Y396741I-30738J24601D01*
G01X757225Y829811D02*
G03X764149Y816680I37663J11469D01*
G01X757224Y829811D02*
G03X764150Y816680I37662J11473D01*
G01X757225Y829811D02*
G03X737264I-9981J-3039D01*
G01X757224D02*
G03X737264I-9980J-3040D01*
G01X730339Y816680D02*
G03X737264Y829811I-30737J24602D01*
G01X730339Y816680D02*
G03X737264Y829811I-30737J24602D01*
G01X730339Y816680D02*
G03X764149I16905J-13531D01*
G01X730339D02*
G03X764150I16905J-13531D01*
G01X721850Y1519685D02*
G03X717913Y1515748I0J-3937D01*
G01X775591Y1519685D02*
X721850D01*
G01D02*
G03X717913Y1515748I0J-3937D01*
G01X775591Y1519685D02*
X721850D01*
G01X713976Y1505118D02*
G03X717913Y1509055I0J3937D01*
G01Y1515748D02*
Y1509055D01*
G01X713976Y1505118D02*
G03X717913Y1509055I0J3937D01*
G01Y1515748D02*
Y1509055D01*
G01X684449Y1515748D02*
G03X680512Y1519685I-3937J0D01*
G01X684449Y1515748D02*
G03X680512Y1519685I-3937J0D01*
G01X684449Y1509055D02*
Y1515748D01*
G01Y1509055D02*
G03X688386Y1505118I3937J0D01*
G01X713976D02*
X688386D01*
G01X684449Y1509055D02*
G03X688386Y1505118I3937J0D01*
G01D02*
X713976D01*
G01X684449Y1515748D02*
Y1509055D01*
G01X791339Y3937D02*
G03X795276Y0I3937J0D01*
G01D02*
X892317D01*
G01X791339Y3937D02*
Y23622D01*
G01Y3937D02*
G03X795276Y0I3937J0D01*
G01X791339Y3937D02*
Y23622D01*
G01X795276Y0D02*
X892317D01*
G01X783465Y54331D02*
G03X791339I3937J0D01*
G01X783465D02*
G03X791339I3937J0D01*
G01Y23622D02*
G03X783465I-3937J0D01*
G01X791339D02*
G03X783465I-3937J0D01*
G01X779528Y0D02*
G03X783465Y3937I0J3937D01*
G01X779528Y0D02*
G03X783465Y3937I0J3937D01*
G01X791339Y54331D02*
Y181890D01*
G01Y54331D02*
Y181890D01*
G01X783465Y3937D02*
Y185827D01*
G01Y3937D02*
Y185827D01*
G01X811024Y181890D02*
G03X822835Y193701I0J11811D01*
G01X791339Y181890D02*
X811024D01*
G01D02*
G03X822835Y193701I0J11811D01*
G01X791339Y181890D02*
X811024D01*
G01X787402Y189764D02*
G03X783465Y185827I0J-3937D01*
G01X787402Y189764D02*
G03X783465Y185827I0J-3937D01*
G01X811024Y189764D02*
G03X814961Y193701I0J3937D01*
G01X787402Y189764D02*
X811024D01*
G01D02*
G03X814961Y193701I0J3937D01*
G01X787402Y189764D02*
X811024D01*
G01X822835Y193701D02*
Y240157D01*
G01Y193701D02*
Y240157D01*
G01X814961Y193701D02*
Y244094D01*
G01Y193701D02*
Y244094D01*
G01X818898Y248031D02*
G03X814961Y244094I0J-3937D01*
G01X818898Y248031D02*
G03X814961Y244094I0J-3937D01*
G01X928098Y240157D02*
X822835D01*
G01X928098D02*
X822835D01*
G01X818898Y248031D02*
X1055118D01*
G01D02*
X818898D01*
G01X954331Y1503937D02*
X817323D01*
G01X954331D02*
X817323D01*
G01X791339Y1519685D02*
G03X787402Y1515748I0J-3937D01*
G01X791339Y1519685D02*
X980315D01*
G01X791339D02*
G03X787402Y1515748I0J-3937D01*
G01X791339Y1519685D02*
X980315D01*
G01X817323Y1503937D02*
G03Y1496063I0J-3937D01*
G01X799213D02*
G03Y1503937I0J3937D01*
G01D02*
X787402D01*
G01Y1515748D02*
Y1503937D01*
G01X799213D02*
X787402D01*
G01X817323D02*
G03Y1496063I0J-3937D01*
G01X799213D02*
G03Y1503937I0J3937D01*
G01X787402Y1515748D02*
Y1503937D01*
G01X779528Y1515748D02*
G03X775591Y1519685I-3937J0D01*
G01X779528Y1515748D02*
G03X775591Y1519685I-3937J0D01*
G01X779528Y1500000D02*
Y1515748D01*
G01Y1500000D02*
G03X783465Y1496063I3937J0D01*
G01X988189D02*
X783465D01*
G01X779528Y1500000D02*
G03X783465Y1496063I3937J0D01*
G01X988189D02*
X783465D01*
G01X779528Y1515748D02*
Y1500000D01*
G01X900191Y0D02*
G03X892317I-3937J0D01*
G01X896254D02*
Y-394D01*
G01Y0D02*
Y394D01*
G01X895762Y0D02*
X896746D01*
G01X900191D02*
G03X892317I-3937J0D01*
G01X900191D02*
X1212598D01*
G01X900191D02*
X1212598D01*
G01X953294Y248031D02*
G03Y240157I1J-3937D01*
G01X1051181D02*
X953294D01*
G01Y248031D02*
G03Y240157I1J-3937D01*
G01X928098D02*
G03Y248031I0J3937D01*
G01Y240157D02*
G03Y248031I0J3937D01*
G01X1051181Y240157D02*
X953294D01*
G01X971398Y718788D02*
G03X951437I-9980J-3040D01*
G01X944512Y705657D02*
G03X951437Y718788I-30737J24602D01*
G01X971398D02*
G03X951437I-9980J-3040D01*
G01X944512Y705657D02*
G03X951437Y718788I-30737J24602D01*
G01X944512Y705657D02*
G03X978323I16905J-13531D01*
G01X944512D02*
G03X978323I16905J-13531D01*
G01X944512Y974161D02*
G03X978323I16905J-13531D01*
G01X944512D02*
G03X978323I16905J-13531D01*
G01X971398Y987292D02*
G03X951437I-9980J-3040D01*
G01X944512Y974161D02*
G03X951437Y987292I-30737J24602D01*
G01X971398D02*
G03X951437I-9980J-3040D01*
G01X944512Y974161D02*
G03X951437Y987292I-30737J24602D01*
G01X954331Y1496063D02*
G03Y1503937I0J3937D01*
G01Y1496063D02*
G03Y1503937I0J3937D01*
G01X1051181Y193701D02*
G03X1062992Y181890I11811J0D01*
G01X1051181Y193701D02*
G03X1062992Y181890I11811J0D01*
G01X1051181Y240157D02*
Y193701D01*
G01Y240157D02*
Y193701D01*
G01X971398Y718788D02*
G03X978323Y705657I37662J11471D01*
G01X971398Y718788D02*
G03X978323Y705657I37662J11470D01*
G01X971398Y987292D02*
G03X978323Y974161I37662J11471D01*
G01X971398Y987292D02*
G03X978323Y974161I37662J11470D01*
G01X1059196Y1519685D02*
X996063D01*
G01X1059196D02*
X996063D01*
G01X984252Y1515748D02*
G03X980315Y1519685I-3937J0D01*
G01X984252Y1515748D02*
G03X980315Y1519685I-3937J0D01*
G01X996063D02*
G03X992126Y1515748I0J-3937D01*
G01X996063Y1519685D02*
G03X992126Y1515748I0J-3937D01*
G01X972441Y1503937D02*
G03Y1496063I0J-3937D01*
G01X984252Y1503937D02*
X972441D01*
G01X984252Y1515748D02*
Y1503937D01*
G01X972441D02*
G03Y1496063I0J-3937D01*
G01X988189D02*
G03X992126Y1500000I0J3937D01*
G01Y1515748D02*
Y1500000D01*
G01X984252Y1515748D02*
Y1503937D01*
G01D02*
X972441D01*
G01X988189Y1496063D02*
G03X992126Y1500000I0J3937D01*
G01Y1515748D02*
Y1500000D01*
G01X1133071Y189764D02*
G03Y181890I0J-3937D01*
G01D02*
X1216535D01*
G01X1133071D02*
X1216535D01*
G01X1133071Y189764D02*
G03Y181890I0J-3937D01*
G01X1102362D02*
G03Y189764I0J3937D01*
G01Y181890D02*
G03Y189764I0J3937D01*
G01X1062992Y181890D02*
X1102362D01*
G01X1062992D02*
X1102362D01*
G01X1059055Y244094D02*
G03X1055118Y248031I-3937J0D01*
G01X1059055Y244094D02*
G03X1055118Y248031I-3937J0D01*
G01X1059055Y244094D02*
Y193701D01*
G01Y244094D02*
Y193701D01*
G01X1062992Y189764D02*
X1220472D01*
G01X1059055Y193701D02*
G03X1062992Y189764I3937J0D01*
G01X1059055Y193701D02*
G03X1062992Y189764I3937J0D01*
G01D02*
X1220472D01*
G01X1085630Y1417323D02*
G03X1089567Y1421260I0J3937D01*
G01X1085630Y1417323D02*
G03X1089567Y1421260I0J3937D01*
G01X1072638D02*
G03X1076575Y1417322I3937J-1D01*
G01X1085630Y1417323D02*
X1076575D01*
G01X1072638Y1421260D02*
G03X1076575Y1417323I3937J0D01*
G01D02*
X1085630D01*
G01X1089567Y1506243D02*
Y1421260D01*
G01Y1506243D02*
Y1421260D01*
G01X1072638D02*
Y1506243D01*
G01D02*
Y1421260D01*
G01X1103009Y1519685D02*
G03X1100225Y1518532I0J-3937D01*
G01X1207283Y1519685D02*
X1103009D01*
G01D02*
G03X1100225Y1518532I0J-3937D01*
G01X1207283Y1519685D02*
X1103009D01*
G01X1090720Y1509027D02*
G03X1089567Y1506243I2784J-2784D01*
G01X1100225Y1518532D02*
X1090720Y1509027D01*
G01D02*
G03X1089567Y1506243I2784J-2784D01*
G01X1100225Y1518532D02*
X1090720Y1509027D01*
G01X1061980Y1518532D02*
G03X1059196Y1519685I-2784J-2784D01*
G01X1061980Y1518532D02*
G03X1059196Y1519685I-2784J-2784D01*
G01X1071485Y1509027D02*
X1061980Y1518532D01*
G01X1072638Y1506243D02*
G03X1071485Y1509027I-3937J0D01*
G01X1072638Y1506243D02*
G03X1071485Y1509027I-3937J0D01*
G01X1061980Y1518532D02*
X1071485Y1509027D01*
G01X1216535Y54331D02*
G03X1224409I3937J0D01*
G01X1216535D02*
Y181890D01*
G01Y54331D02*
Y181890D01*
G01Y54331D02*
G03X1224409I3937J0D01*
G01Y23622D02*
G03X1216535I-3937J0D01*
G01X1224409D02*
G03X1216535I-3937J0D01*
G01X1212598Y0D02*
G03X1216535Y3937I0J3937D01*
G01D02*
Y23622D01*
G01X1212598Y0D02*
G03X1216535Y3937I0J3937D01*
G01X1224409D02*
G03X1228346Y0I3937J0D01*
G01X1224409Y185827D02*
Y3937D01*
G01X1216535D02*
Y23622D01*
G01X1224409Y3937D02*
G03X1228346Y0I3937J0D01*
G01X1224409Y3937D02*
Y185827D01*
G01X1228346Y0D02*
X1930906D01*
G01X1228346D02*
X1930906D01*
G01X1224409Y185827D02*
G03X1220472Y189764I-3937J0D01*
G01X1224409Y185827D02*
G03X1220472Y189764I-3937J0D01*
G01X1164984Y383609D02*
G03X1198795I16906J-13530D01*
G01X1164984D02*
G03X1198795I16906J-13530D01*
G01X1191870Y396741D02*
G03X1198795Y383610I37662J11471D01*
G01X1191870Y396741D02*
G03X1198795Y383609I37663J11469D01*
G01X1191870Y396741D02*
G03X1171909I-9980J-3040D01*
G01X1164984Y383610D02*
G03X1171909Y396741I-30737J24602D01*
G01X1191870D02*
G03X1171909I-9980J-3040D01*
G01X1164984Y383609D02*
G03X1171909Y396741I-30737J24601D01*
G01X1164984Y974161D02*
G03X1198795I16906J-13531D01*
G01X1164984D02*
G03X1198795I16906J-13531D01*
G01X1191870Y987292D02*
G03X1198795Y974161I37662J11471D01*
G01X1191870Y987292D02*
G03X1198795Y974161I37662J11471D01*
G01X1191870Y987292D02*
G03X1171909I-9980J-3040D01*
G01X1164984Y974161D02*
G03X1171909Y987292I-30737J24602D01*
G01X1191870D02*
G03X1171909I-9980J-3040D01*
G01X1164984Y974161D02*
G03X1171909Y987292I-30737J24601D01*
G01X1240748Y1505118D02*
G03X1244685Y1509055I0J3937D01*
G01X1240748Y1505118D02*
G03X1244685Y1509055I0J3937D01*
G01X1211220Y1515748D02*
G03X1207283Y1519685I-3937J0D01*
G01X1211220Y1515748D02*
G03X1207283Y1519685I-3937J0D01*
G01X1211220Y1509055D02*
Y1515748D01*
G01Y1509055D02*
G03X1215157Y1505118I3937J0D01*
G01X1240748D02*
X1215157D01*
G01X1211220Y1509055D02*
G03X1215157Y1505118I3937J0D01*
G01D02*
X1240748D01*
G01X1211220Y1515748D02*
Y1509055D01*
G01X1311851Y277843D02*
G03X1318775Y264712I37663J11469D01*
G01X1311850Y277843D02*
G03X1318776Y264712I37661J11473D01*
G01X1311851Y277843D02*
G03X1291890I-9980J-3040D01*
G01X1284965Y264712D02*
G03X1291890Y277843I-30737J24602D01*
G01X1311850D02*
G03X1291890I-9980J-3040D01*
G01X1284965Y264712D02*
G03X1291890Y277843I-30737J24602D01*
G01X1284965Y264712D02*
G03X1318775I16905J-13531D01*
G01X1284965D02*
G03X1318776I16906J-13531D01*
G01X1311851Y730599D02*
G03X1318775Y717468I37663J11469D01*
G01X1311850Y730599D02*
G03X1318776Y717468I37661J11473D01*
G01X1311851Y730599D02*
G03X1291890I-9980J-3040D01*
G01X1284965Y717468D02*
G03X1291891Y730599I-30736J24604D01*
G01X1311850D02*
G03X1291890I-9980J-3040D01*
G01X1284965Y717468D02*
G03X1291890Y730599I-30737J24602D01*
G01X1284965Y717468D02*
G03X1318775I16905J-13531D01*
G01X1284965D02*
G03X1318776I16906J-13531D01*
G01X1284965Y1170224D02*
G03X1318775I16905J-13531D01*
G01X1284965D02*
G03X1318776I16906J-13531D01*
G01X1311851Y1183355D02*
G03X1318775Y1170224I37663J11469D01*
G01X1311850Y1183355D02*
G03X1318776Y1170224I37661J11473D01*
G01X1311851Y1183355D02*
G03X1291890I-9980J-3040D01*
G01X1311850D02*
G03X1291890I-9980J-3040D01*
G01X1284965Y1170224D02*
G03X1291890Y1183355I-30737J24602D01*
G01X1284965Y1170224D02*
G03X1291890Y1183355I-30737J24602D01*
G01X1248622Y1519685D02*
G03X1244685Y1515748I0J-3937D01*
G01X1427953Y1519685D02*
X1248622D01*
G01D02*
G03X1244685Y1515748I0J-3937D01*
G01X1427953Y1519685D02*
X1248622D01*
G01X1244685Y1515748D02*
Y1509055D01*
G01Y1515748D02*
Y1509055D01*
G01X1431890Y1515748D02*
G03X1427953Y1519685I-3937J0D01*
G01X1431890Y1515748D02*
G03X1427953Y1519685I-3937J0D01*
G01X1431890Y1500000D02*
Y1515748D01*
G01Y1500000D02*
G03X1435827Y1496063I3937J0D01*
G01X1431890Y1500000D02*
G03X1435827Y1496063I3937J0D01*
G01X1431890Y1515748D02*
Y1500000D01*
G01X1532996Y264712D02*
G03X1566807I16906J-13531D01*
G01X1532996D02*
G03X1566807I16906J-13531D01*
G01X1532996Y717468D02*
G03X1566807I16906J-13531D01*
G01X1532996D02*
G03X1566807I16906J-13531D01*
G01X1532996Y1170224D02*
G03X1566807I16906J-13531D01*
G01X1532996D02*
G03X1566807I16906J-13531D01*
G01X1469685Y1503937D02*
G03Y1496063I0J-3937D01*
G01X1451575D02*
G03Y1503937I0J3937D01*
G01X1606693D02*
X1469685D01*
G01X1606693D02*
X1469685D01*
G01D02*
G03Y1496063I0J-3937D01*
G01X1451575D02*
G03Y1503937I0J3937D01*
G01X1443701Y1519685D02*
G03X1439764Y1515748I0J-3937D01*
G01X1443701Y1519685D02*
X1632677D01*
G01X1443701D02*
G03X1439764Y1515748I0J-3937D01*
G01X1443701Y1519685D02*
X1632677D01*
G01X1451575Y1503937D02*
X1439764D01*
G01Y1515748D02*
Y1503937D01*
G01X1451575D02*
X1439764D01*
G01X1640551Y1496063D02*
X1435827D01*
G01X1439764Y1515748D02*
Y1503937D01*
G01X1640551Y1496063D02*
X1435827D01*
G01X1559882Y277843D02*
G03X1566807Y264712I37662J11471D01*
G01X1559882Y277843D02*
G03X1539921I-9980J-3040D01*
G01X1559882D02*
G03X1566807Y264712I37662J11471D01*
G01X1559882Y277843D02*
G03X1539921I-9980J-3040D01*
G01X1532996Y264712D02*
G03X1539921Y277843I-30737J24602D01*
G01X1532996Y264712D02*
G03X1539921Y277843I-30737J24602D01*
G01X1559882Y730599D02*
G03X1566807Y717468I37662J11471D01*
G01X1559882Y730599D02*
G03X1539921I-9980J-3040D01*
G01X1559882D02*
G03X1566807Y717468I37662J11471D01*
G01X1559882Y730599D02*
G03X1539921I-9980J-3040D01*
G01X1532996Y717468D02*
G03X1539921Y730599I-30737J24601D01*
G01X1532996Y717468D02*
G03X1539921Y730599I-30737J24601D01*
G01X1559882Y1183355D02*
G03X1539921I-9980J-3040D01*
G01X1559882D02*
G03X1539921I-9980J-3040D01*
G01X1559882D02*
G03X1566807Y1170224I37662J11471D01*
G01X1559882Y1183355D02*
G03X1566807Y1170224I37662J11471D01*
G01X1532996D02*
G03X1539921Y1183355I-30737J24602D01*
G01X1532996Y1170224D02*
G03X1539921Y1183355I-30737J24601D01*
G01X1636614Y1503937D02*
X1624803D01*
G01X1636614D02*
X1624803D01*
G01D02*
G03Y1496063I0J-3937D01*
G01X1606693D02*
G03Y1503937I0J3937D01*
G01X1624803D02*
G03Y1496063I0J-3937D01*
G01X1606693D02*
G03Y1503937I0J3937D01*
G01X1636614Y1515748D02*
G03X1632677Y1519685I-3937J0D01*
G01X1636614Y1515748D02*
G03X1632677Y1519685I-3937J0D01*
G01X1648425D02*
G03X1644488Y1515748I0J-3937D01*
G01X1827756Y1519685D02*
X1648425D01*
G01D02*
G03X1644488Y1515748I0J-3937D01*
G01X1827756Y1519685D02*
X1648425D01*
G01X1636614Y1515748D02*
Y1503937D01*
G01X1640551Y1496063D02*
G03X1644488Y1500000I0J3937D01*
G01Y1515748D02*
Y1500000D01*
G01X1636614Y1515748D02*
Y1503937D01*
G01X1640551Y1496063D02*
G03X1644488Y1500000I0J3937D01*
G01Y1515748D02*
Y1500000D01*
G01X1807914Y277843D02*
G03X1814838Y264712I37663J11469D01*
G01X1807913Y277843D02*
G03X1814839Y264712I37661J11473D01*
G01X1807914Y277843D02*
G03X1787953I-9980J-3040D01*
G01X1781028Y264712D02*
G03X1787953Y277843I-30737J24602D01*
G01X1807913D02*
G03X1787953I-9980J-3040D01*
G01X1781028Y264712D02*
G03X1787953Y277843I-30737J24602D01*
G01X1781028Y264712D02*
G03X1814839I16906J-13531D01*
G01X1781028D02*
G03X1814839I16906J-13531D01*
G01X1807914Y730599D02*
G03X1814838Y717468I37663J11469D01*
G01X1807913Y730599D02*
G03X1814839Y717468I37661J11473D01*
G01X1807914Y730599D02*
G03X1787953I-9980J-3040D01*
G01X1781028Y717468D02*
G03X1787954Y730599I-30736J24604D01*
G01X1807913D02*
G03X1787953I-9980J-3040D01*
G01X1781028Y717468D02*
G03X1787953Y730599I-30737J24602D01*
G01X1781028Y717468D02*
G03X1814838I16905J-13531D01*
G01X1781028D02*
G03X1814839I16906J-13531D01*
G01X1781028Y1170224D02*
G03X1814838I16905J-13531D01*
G01X1781028D02*
G03X1814839I16906J-13531D01*
G01X1807914Y1183355D02*
G03X1814838Y1170224I37662J11468D01*
G01X1807913Y1183355D02*
G03X1814839Y1170224I37661J11473D01*
G01X1807914Y1183355D02*
G03X1787953I-9980J-3040D01*
G01X1807913D02*
G03X1787953I-9980J-3040D01*
G01X1781028Y1170224D02*
G03X1787953Y1183355I-30737J24602D01*
G01X1781028Y1170224D02*
G03X1787953Y1183355I-30737J24602D01*
G01X1869094Y1519685D02*
G03X1865157Y1515748I0J-3937D01*
G01X1919094Y1519685D02*
X1869094D01*
G01D02*
G03X1865157Y1515748I0J-3937D01*
G01X1919094Y1519685D02*
X1869094D01*
G01X1865157Y1515748D02*
Y1509055D01*
G01Y1515748D02*
Y1509055D01*
G01X1861220Y1505118D02*
X1835630D01*
G01X1861220D02*
G03X1865157Y1509055I0J3937D01*
G01X1861220Y1505118D02*
G03X1865157Y1509055I0J3937D01*
G01X1835630Y1505118D02*
X1861220D01*
G01X1831693Y1515748D02*
G03X1827756Y1519685I-3937J0D01*
G01X1831693Y1515748D02*
G03X1827756Y1519685I-3937J0D01*
G01X1831693Y1509055D02*
Y1515748D01*
G01Y1509055D02*
G03X1835630Y1505118I3937J0D01*
G01X1831693Y1509055D02*
G03X1835630Y1505118I3937J0D01*
G01X1831693Y1515748D02*
Y1509055D01*
G01X1930906Y0D02*
G03X1934843Y3937I0J3937D01*
G01X1930906Y0D02*
G03X1934843Y3937I0J3937D01*
G01D02*
Y1456693D01*
G01Y3937D02*
Y1456693D01*
G01X1930906Y1460630D02*
X1926969D01*
G01X1934843Y1456693D02*
G03X1930906Y1460630I-3937J0D01*
G01X1934843Y1456693D02*
G03X1930906Y1460630I-3937J0D01*
G01D02*
X1926969D01*
G01X1923031Y1515748D02*
G03X1919094Y1519685I-3937J0D01*
G01X1923031Y1515748D02*
G03X1919094Y1519685I-3937J0D01*
G01X1923031Y1464567D02*
Y1515748D01*
G01Y1464567D02*
G03X1926969Y1460630I3937J0D01*
G01X1923031Y1464567D02*
G03X1926969Y1460630I3937J0D01*
G01X1923031Y1515748D02*
Y1464567D01*
G54D12*
G01X59474Y838032D02*
X171032D01*
G01X46442Y825000D02*
X59474Y838032D01*
G01X169442Y833942D02*
Y824700D01*
G01X198214Y862714D02*
X169442Y833942D01*
G01X171032Y838032D02*
X197439Y864439D01*
G01X788187Y862714D02*
X198214D01*
G01X197439Y864439D02*
X788902D01*
G01X309000Y825000D02*
X344989Y860989D01*
G01X294542Y825000D02*
X309000D01*
G01X344989Y860989D02*
X787472D01*
G01X427444Y824444D02*
X418742D01*
G01X462264Y859264D02*
X427444Y824444D01*
G01X786757Y859264D02*
X462264D01*
G01X677100Y675600D02*
X666900Y665400D01*
G01X724261Y757011D02*
X646680Y679430D01*
G01X659642Y833642D02*
Y824700D01*
G01X681814Y855814D02*
X659642Y833642D01*
G01X582648Y825223D02*
X614964Y857539D01*
G01D02*
X786042D01*
G01X639900Y1479900D02*
X706786D01*
G01X628500Y1468500D02*
X639900Y1479900D01*
G01X730721Y748121D02*
X728100Y745500D01*
G01X753738Y748121D02*
X730721D01*
G01X791616Y785999D02*
X753738Y748121D01*
G01X725700Y741900D02*
X723000Y739200D01*
G01X725700Y745911D02*
Y741900D01*
G01X729635Y749846D02*
X725700Y745911D01*
G01X753023Y749846D02*
X729635D01*
G01X790901Y787724D02*
X753023Y749846D01*
G01X754575Y730950D02*
X709871Y686246D01*
G01X779153Y730950D02*
X754575D01*
G01X718200Y746820D02*
Y744000D01*
G01X726666Y755286D02*
X718200Y746820D01*
G01X751143Y755286D02*
X726666D01*
G01X788757Y792900D02*
X751143Y755286D01*
G01X708000Y675600D02*
X677100D01*
G01X761625Y729225D02*
X708000Y675600D01*
G01X779868Y729225D02*
X761625D01*
G01X720600Y741000D02*
X718100Y738500D01*
G01X720600Y746780D02*
Y741000D01*
G01X727116Y753296D02*
X720600Y746780D01*
G01X751593Y753296D02*
X727116D01*
G01X789471Y791174D02*
X751593Y753296D01*
G01X733271Y746396D02*
X728175Y741300D01*
G01X754453Y746396D02*
X733271D01*
G01X791582Y783525D02*
X754453Y746396D01*
G01X723974Y744374D02*
X723300Y743700D01*
G01X723974Y746625D02*
Y744374D01*
G01X728920Y751571D02*
X723974Y746625D01*
G01X752308Y751571D02*
X728920D01*
G01X790186Y789449D02*
X752308Y751571D01*
G01X750428Y757011D02*
X724261D01*
G01X794337Y800920D02*
X750428Y757011D01*
G01X785327Y855814D02*
X681814D01*
G01X723233Y878233D02*
X801236D01*
G01X717700Y872700D02*
X723233Y878233D01*
G01X701700Y872700D02*
X717700D01*
G01X725983Y874783D02*
X799806D01*
G01X723600Y872400D02*
X725983Y874783D01*
G01X715375Y870975D02*
X714500Y870100D01*
G01X718415Y870975D02*
X715375D01*
G01X723948Y876508D02*
X718415Y870975D01*
G01X800521Y876508D02*
X723948D01*
G01X728358Y873058D02*
X727600Y872300D01*
G01X799091Y873058D02*
X728358D01*
G01X745000Y1463500D02*
Y1463000D01*
G01X738767Y1469733D02*
X745000Y1463500D01*
G01X716953Y1469733D02*
X738767D01*
G01X706786Y1479900D02*
X716953Y1469733D01*
G01X863710Y491400D02*
X858740Y486430D01*
G01X817890Y633700D02*
X892400D01*
G01X809840Y641750D02*
X817890Y633700D01*
G01X799998Y641750D02*
X809840D01*
G01X798475Y640227D02*
X799998Y641750D01*
G01X819380Y629400D02*
X872430D01*
G01X810280Y638500D02*
X819380Y629400D01*
G01X799559Y638500D02*
X810280D01*
G01X799298Y638239D02*
X799559Y638500D01*
G01X796631Y638239D02*
X799298D01*
G01X794886Y639984D02*
X796631Y638239D01*
G01X794883Y639984D02*
X794886D01*
G01X790078Y741875D02*
X779153Y730950D01*
G01X790078Y741876D02*
Y741875D01*
G01X797496Y749294D02*
X790078Y741876D01*
G01X874694Y749294D02*
X797496D01*
G01X798212Y747569D02*
X779868Y729225D01*
G01X875409Y747569D02*
X798212D01*
G01X898799Y785999D02*
X791616D01*
G01X897724Y787724D02*
X790901D01*
G01X893400Y792900D02*
X788757D01*
G01X842191Y843649D02*
X828100Y857740D01*
G01X875368Y843649D02*
X842191D01*
G01X818493Y832408D02*
X788187Y862714D01*
G01X899112Y832408D02*
X818493D01*
G01X815633Y825508D02*
X785327Y855814D01*
G01X889605Y825508D02*
X815633D01*
G01X819208Y834133D02*
X900198D01*
G01X788902Y864439D02*
X819208Y834133D01*
G01X817063Y828958D02*
X786757Y859264D01*
G01X894468Y828958D02*
X817063D01*
G01X895174Y791174D02*
X789471D01*
G01X816348Y827233D02*
X891880D01*
G01X786042Y857539D02*
X816348Y827233D01*
G01X909225Y783525D02*
X791582D01*
G01X896744Y789449D02*
X790186D01*
G01X794337Y809822D02*
Y800920D01*
G01X805975Y821460D02*
X794337Y809822D01*
G01X821875Y821460D02*
X805975D01*
G01X823765Y819570D02*
X821875Y821460D01*
G01X869266Y819570D02*
X823765D01*
G01X841476Y841924D02*
X826000Y857400D01*
G01X860713Y841924D02*
X841476D01*
G01X863778Y838859D02*
X860713Y841924D01*
G01X817778Y830683D02*
X897106D01*
G01X787472Y860989D02*
X817778Y830683D01*
G01X798813Y839888D02*
X778735D01*
G01X815181Y823520D02*
X798813Y839888D01*
G01X822255Y823520D02*
X815181D01*
G01X824275Y821500D02*
X822255Y823520D01*
G01X868639Y821500D02*
X824275D01*
G01X828100Y859840D02*
X825900Y862040D01*
G01X828100Y857740D02*
Y859840D01*
G01X833989Y866381D02*
X886825D01*
G01X828658Y871712D02*
X833989Y866381D01*
G01X807757Y871712D02*
X828658D01*
G01X801236Y878233D02*
X807757Y871712D01*
G01X832559Y862931D02*
X888255D01*
G01X827228Y868262D02*
X832559Y862931D01*
G01X806327Y868262D02*
X827228D01*
G01X799806Y874783D02*
X806327Y868262D01*
G01X807042Y869987D02*
X800521Y876508D01*
G01X827943Y869987D02*
X807042D01*
G01X833274Y864656D02*
X827943Y869987D01*
G01X887540Y864656D02*
X833274D01*
G01X805612Y866537D02*
X799091Y873058D01*
G01X826513Y866537D02*
X805612D01*
G01X831844Y861206D02*
X826513Y866537D01*
G01X890117Y861206D02*
X831844D01*
G01X818867Y1473251D02*
X939144D01*
G01X797438Y1451822D02*
X818867Y1473251D01*
G01X772361Y1451822D02*
X797438D01*
G01X772361Y1451972D02*
Y1451822D01*
G01X909281Y267548D02*
Y317974D01*
G01X904725Y262992D02*
X909281Y267548D01*
G01X893116Y282475D02*
Y318061D01*
G01X897638Y277953D02*
X893116Y282475D01*
G01X902184Y276987D02*
Y314686D01*
G01X897638Y272441D02*
X902184Y276987D01*
G01X916300Y282442D02*
Y322463D01*
G01X911811Y277953D02*
X916300Y282442D01*
G01X907306Y271085D02*
Y318439D01*
G01X904725Y268504D02*
X907306Y271085D01*
G01X897638Y282283D02*
X895091Y284830D01*
G01X919600Y280230D02*
Y323265D01*
G01X911811Y272441D02*
X919600Y280230D01*
G01X909281Y317974D02*
X992820Y401513D01*
G01X898059Y339892D02*
Y343029D01*
G01X894127Y335960D02*
X898059Y339892D01*
G01X894127Y319072D02*
Y335960D01*
G01X893116Y318061D02*
X894127Y319072D01*
G01X904725Y318298D02*
X991390Y404963D01*
G01X904725Y315354D02*
Y318298D01*
G01X909560Y354256D02*
X909423Y354393D01*
G01X909560Y337772D02*
Y354256D01*
G01X903994Y332206D02*
X909560Y337772D01*
G01X903994Y321917D02*
Y332206D01*
G01X901920Y319843D02*
X903994Y321917D01*
G01X901920Y314950D02*
Y319843D01*
G01X902184Y314686D02*
X901920Y314950D01*
G01X906712Y351490D02*
X906616Y351586D01*
G01X906712Y338256D02*
Y351490D01*
G01X901245Y332789D02*
X906712Y338256D01*
G01X901245Y322825D02*
Y332789D01*
G01X899077Y320657D02*
X901245Y322825D01*
G01X899077Y314306D02*
Y320657D01*
G01X900209Y313174D02*
X899077Y314306D01*
G01X900209Y289185D02*
Y313174D01*
G01X897638Y286614D02*
X900209Y289185D01*
G01X896071Y344079D02*
X936148Y384156D01*
G01X896071Y340783D02*
Y344079D01*
G01X892089Y336801D02*
X896071Y340783D01*
G01X892089Y320593D02*
Y336801D01*
G01X888038Y316542D02*
X892089Y320593D01*
G01X888038Y308026D02*
Y316542D01*
G01X890552Y305512D02*
X888038Y308026D01*
G01X916300Y322463D02*
X993625Y399788D01*
G01X907306Y318439D02*
X992105Y403238D01*
G01X902184Y341072D02*
Y347219D01*
G01X897103Y335991D02*
X902184Y341072D01*
G01X897103Y314477D02*
Y335991D01*
G01X895091Y312465D02*
X897103Y314477D01*
G01X895091Y284830D02*
Y312465D01*
G01X919600Y323265D02*
X994398Y398063D01*
G01X936148Y384156D02*
X959989D01*
G01X863710Y497981D02*
Y491400D01*
G01X884906Y519177D02*
X863710Y497981D01*
G01X898035Y519177D02*
X884906D01*
G01X932811Y553953D02*
X898035Y519177D01*
G01X998811Y553953D02*
X932811D01*
G01X873255Y630225D02*
X884801D01*
G01X872430Y629400D02*
X873255Y630225D01*
G01X896100Y770700D02*
X874694Y749294D01*
G01X897825Y769985D02*
X875409Y747569D01*
G01X902100Y789300D02*
X898799Y785999D01*
G01X907200Y789300D02*
X902100D01*
G01X907800Y788700D02*
X907200Y789300D01*
G01X901395Y791395D02*
X897724Y787724D01*
G01X911356Y791395D02*
X901395D01*
G01X912762Y792801D02*
X911356Y791395D01*
G01X896100Y776400D02*
Y770700D01*
G01X901500Y781800D02*
X896100Y776400D01*
G01X911718Y781800D02*
X901500D01*
G01X925218Y795300D02*
X911718Y781800D01*
G01X934800Y795300D02*
X925218D01*
G01X903700Y803200D02*
X893400Y792900D01*
G01X876862Y842155D02*
X875368Y843649D01*
G01X920057Y811463D02*
X899112Y832408D01*
G01X921047Y811463D02*
X920057D01*
G01X871981Y853984D02*
X870200Y852203D01*
G01X897459Y853984D02*
X871981D01*
G01X911075Y867600D02*
X897459Y853984D01*
G01X901800Y813313D02*
X889605Y825508D01*
G01X902560Y813313D02*
X901800D01*
G01X903300Y765200D02*
Y763200D01*
G01X907500Y769400D02*
X903300Y765200D01*
G01X914200Y769400D02*
X907500D01*
G01X927800Y783000D02*
X914200Y769400D01*
G01X934400Y783000D02*
X927800D01*
G01X947600Y796200D02*
X934400Y783000D01*
G01X947600Y827502D02*
Y796200D01*
G01X943294Y831808D02*
X947600Y827502D01*
G01X943294Y838833D02*
Y831808D01*
G01X919461Y817581D02*
X924484Y812558D01*
G01X916750Y817581D02*
X919461D01*
G01X900198Y834133D02*
X916750Y817581D01*
G01X897825Y775225D02*
Y769985D01*
G01X902575Y779975D02*
X897825Y775225D01*
G01X912333Y779975D02*
X902575D01*
G01X923858Y791500D02*
X912333Y779975D01*
G01X931800Y791500D02*
X923858D01*
G01X913059Y810367D02*
X894468Y828958D01*
G01X900658Y796658D02*
X895174Y791174D01*
G01X905864Y796658D02*
X900658D01*
G01X909094Y799888D02*
X905864Y796658D01*
G01X909094Y799894D02*
Y799888D01*
G01X909144Y799944D02*
X909094Y799894D01*
G01X909144Y803346D02*
Y799944D01*
G01X905506Y813444D02*
X906166Y812784D01*
G01X905506Y813607D02*
Y813444D01*
G01X891880Y827233D02*
X905506Y813607D01*
G01X912030Y786330D02*
X909225Y783525D01*
G01X912030Y787650D02*
Y786330D01*
G01X901233Y793938D02*
X896744Y789449D01*
G01X903221Y793938D02*
X901233D01*
G01X869989Y818847D02*
X869266Y819570D01*
G01X881702Y838859D02*
X863778D01*
G01X897106Y830683D02*
X916855Y810934D01*
G01X867480Y855925D02*
X866655Y855100D01*
G01X894233Y855925D02*
X867480D01*
G01X894234Y855924D02*
X894233Y855925D01*
G01X896366Y855924D02*
X894234D01*
G01X910842Y870400D02*
X896366Y855924D01*
G01X870001Y822862D02*
X868639Y821500D01*
G01X939215Y867600D02*
X911075D01*
G01X943765Y872150D02*
X939215Y867600D01*
G01X943766Y872150D02*
X943765D01*
G01X945471Y873855D02*
X943766Y872150D01*
G01X960745Y873855D02*
X945471D01*
G01X892329Y867394D02*
X894317Y865406D01*
G01X887838Y867394D02*
X892329D01*
G01X886825Y866381D02*
X887838Y867394D01*
G01X892329Y863194D02*
X894317Y861206D01*
G01X888518Y863194D02*
X892329D01*
G01X888255Y862931D02*
X888518Y863194D01*
G01X888290Y865406D02*
X887540Y864656D01*
G01X890117Y865406D02*
X888290D01*
G01X939575Y870400D02*
X910842D01*
G01X944755Y875580D02*
X939575Y870400D01*
G01X962720Y875580D02*
X944755D01*
G01X942315Y1476422D02*
X999102D01*
G01X939144Y1473251D02*
X942315Y1476422D01*
G01X1032313Y401513D02*
X1094204Y463404D01*
G01X992820Y401513D02*
X1032313D01*
G01X1030883Y404963D02*
X1093221Y467301D01*
G01X991390Y404963D02*
X1030883D01*
G01X1027736Y412264D02*
X1090623Y475151D01*
G01X988097Y412264D02*
X1027736D01*
G01X959989Y384156D02*
X988097Y412264D01*
G01X1033028Y399788D02*
X1086170Y452930D01*
G01X993625Y399788D02*
X1033028D01*
G01X1031598Y403238D02*
X1093935Y465575D01*
G01X992105Y403238D02*
X1031598D01*
G01X1034097Y398063D02*
X1087240Y451206D01*
G01X994398Y398063D02*
X1034097D01*
G01X1035860Y591002D02*
X998811Y553953D01*
G01X1146000Y591002D02*
X1035860D01*
G01X964900Y869700D02*
X960745Y873855D01*
G01X1067159Y869700D02*
X964900D01*
G01X1022080Y960728D02*
X1030862Y951946D01*
G01X966875Y871425D02*
X962720Y875580D01*
G01X1030167Y871425D02*
X966875D01*
G01X1033442Y874700D02*
X1030167Y871425D01*
G01X1039500Y874700D02*
X1033442D01*
G01X1042775Y871425D02*
X1067874D01*
G01X1039500Y874700D02*
X1042775Y871425D01*
G01X1047128Y1025934D02*
Y1236512D01*
G01X1096751Y976311D02*
X1047128Y1025934D01*
G01Y1236512D02*
X1084638Y1274022D01*
G01X1049260Y1472605D02*
Y1466691D01*
G01X1036690Y1485175D02*
X1049260Y1472605D01*
G01X1007855Y1485175D02*
X1036690D01*
G01X999102Y1476422D02*
X1007855Y1485175D01*
G01X1053948Y1443004D02*
X1048553Y1448399D01*
G01X1094204Y463404D02*
X1152162D01*
G01X1125201Y467301D02*
X1130800Y472900D01*
G01X1093221Y467301D02*
X1125201D01*
G01X1129918Y452931D02*
X1136000Y446849D01*
G01X1086525Y452931D02*
X1129918D01*
G01X1086524Y452930D02*
X1086525Y452931D01*
G01X1086170Y452930D02*
X1086524D01*
G01X1093935Y465575D02*
X1149705D01*
G01X1127394Y451206D02*
X1131800Y446800D01*
G01X1087240Y451206D02*
X1127394D01*
G01X1102677Y487212D02*
Y487116D01*
G01X1103870Y487212D02*
X1102677D01*
G01X1110497Y493839D02*
X1103870Y487212D01*
G01X1114816Y493839D02*
X1110497D01*
G01X1175500Y554523D02*
X1114816Y493839D01*
G01X1119269Y486263D02*
X1183077Y550071D01*
G01X1114184Y486263D02*
X1119269D01*
G01X1103072Y475151D02*
X1114184Y486263D01*
G01X1090623Y475151D02*
X1103072D01*
G01X1108650Y677776D02*
X1156426Y630000D01*
G01X1134600Y642768D02*
Y618747D01*
G01X1118505Y658863D02*
X1134600Y642768D01*
G01X1151824Y596826D02*
X1146000Y591002D01*
G01X1107896Y675413D02*
X1151824Y631485D01*
G01X1114920Y658882D02*
X1114905D01*
G01X1129500Y644302D02*
X1114920Y658882D01*
G01X1129500Y619200D02*
Y644302D01*
G01X1107674Y677776D02*
X1108650D01*
G01X1103770Y675413D02*
X1107896D01*
G01X1072485Y864374D02*
X1067159Y869700D01*
G01X1082100Y864374D02*
X1072485D01*
G01X1083309Y865583D02*
X1082100Y864374D01*
G01X1115749Y865583D02*
X1083309D01*
G01X1119042Y868876D02*
X1115749Y865583D01*
G01X1110932Y871474D02*
X1113530Y868876D01*
G01X1092127Y871474D02*
X1110932D01*
G01X1091232Y870579D02*
X1092127Y871474D01*
G01X1068720Y870579D02*
X1091232D01*
G01X1067874Y871425D02*
X1068720Y870579D01*
G01X1096751Y958549D02*
Y976311D01*
G01X1101600Y953700D02*
X1096751Y958549D01*
G01X1091586Y1232413D02*
X1108586Y1249413D01*
G01X1091586Y1217770D02*
Y1232413D01*
G01X1069347Y1195531D02*
X1091586Y1217770D01*
G01X1069347Y1192308D02*
Y1195531D01*
G01X1068569Y1191530D02*
X1069347Y1192308D01*
G01X1072931Y1196675D02*
Y1191482D01*
G01X1093312Y1217056D02*
X1072931Y1196675D01*
G01X1093312Y1231698D02*
Y1217056D01*
G01X1109302Y1247688D02*
X1093312Y1231698D01*
G01X1108586Y1249413D02*
X1230814D01*
G01X1233102Y1247688D02*
X1109302D01*
G01X1080092Y1305753D02*
Y1381727D01*
G01X1084638Y1301207D02*
X1080092Y1305753D01*
G01X1084638Y1274022D02*
Y1301207D01*
G01X1053948Y1407871D02*
Y1443004D01*
G01X1080092Y1381727D02*
X1053948Y1407871D01*
G01X1156110Y467352D02*
Y473330D01*
G01X1152162Y463404D02*
X1156110Y467352D01*
G01X1149705Y465575D02*
X1152600Y468470D01*
G01X1175500Y583310D02*
Y554523D01*
G01X1183077Y550071D02*
Y592065D01*
G01X1156426Y602384D02*
X1175500Y583310D01*
G01X1156426Y630000D02*
Y602384D01*
G01X1183077Y592065D02*
X1177350Y597792D01*
G01X1151824Y631485D02*
Y596826D01*
G01X1230814Y1249413D02*
X1293000Y1311599D01*
G01X1273402Y1287988D02*
X1233102Y1247688D01*
G01X1293000Y1311599D02*
Y1420895D01*
G01X1672004Y1287988D02*
X1273402D01*
G01X1293000Y1420895D02*
X1277086Y1436809D01*
G01X1290662Y1482612D02*
X1289574Y1483700D01*
G01X1290662Y1460566D02*
Y1482612D01*
G01X1280884Y1450788D02*
X1290662Y1460566D01*
G01X1280184Y1450788D02*
X1280884D01*
G01X1277086Y1447690D02*
X1280184Y1450788D01*
G01X1277086Y1436809D02*
Y1447690D01*
G01X1676511Y1292495D02*
X1672004Y1287988D01*
M02*
